(lib_symbols
	(symbol "antmicroCapacitors0402:C_100n_0402" (pin_numbers hide) (pin_names hide) (in_bom yes) (on_board yes)
      (property "Reference" "C" (at 20.32 -5.08 0)
        (effects (font (size 1.27 1.27) (thickness 0.15)) (justify left bottom))
      )
      (property "Value" "C_100n_0402" (at 20.32 -10.16 0)
        (effects (font (size 1.27 1.27) (thickness 0.15)) (justify left bottom) hide)
      )
      (property "Footprint" "antmicro-footprints:C_0402_1005Metric" (at 20.32 -12.7 0)
        (effects (font (size 1.27 1.27) (thickness 0.15)) (justify left bottom) hide)
      )
      (property "Datasheet" "https://www.murata.com/products/productdetail?partno=GRM155R61H104KE14%23" (at 20.32 -15.24 0)
        (effects (font (size 1.27 1.27) (thickness 0.15)) (justify left bottom) hide)
      )
      (property "MPN" "GRM155R61H104KE14D" (at 20.32 -17.78 0)
        (effects (font (size 1.27 1.27) (thickness 0.15)) (justify left bottom) hide)
      )
      (property "Manufacturer" "Murata" (at 20.32 -20.32 0)
        (effects (font (size 1.27 1.27) (thickness 0.15)) (justify left bottom) hide)
      )
      (property "License" "Apache-2.0" (at 20.32 -22.86 0)
        (effects (font (size 1.27 1.27) (thickness 0.15)) (justify left bottom) hide)
      )
      (property "Author" "Antmicro" (at 20.32 -25.4 0)
        (effects (font (size 1.27 1.27) (thickness 0.15)) (justify left bottom) hide)
      )
      (property "Val" "100n" (at 20.32 -7.62 0)
        (effects (font (size 1.27 1.27) (thickness 0.15)) (justify left bottom))
      )
      (property "Voltage" "50V" (at 20.32 -27.94 0)
        (effects (font (size 1.27 1.27)) (justify left bottom) hide)
      )
      (property "Dielectric" "X5R" (at 20.32 -30.48 0)
        (effects (font (size 1.27 1.27)) (justify left bottom) hide)
      )
      (property "ki_keywords" "0402, SMT, CAPACITOR, PASSIVE, CERAMIC, MLCC" (at 0 0 0)
        (effects (font (size 1.27 1.27)) hide)
      )
      (property "ki_description" "SMD Multilayer Ceramic Capacitor, 0.1 µF, 50 V, 0402 [1005 Metric], ± 10%, X5R, GRM Series" (at 0 0 0)
        (effects (font (size 1.27 1.27)) hide)
      )
      (symbol "C_100n_0402_0_1"
        (polyline
          (pts
            (xy 2.032 -1.524)
            (xy 2.032 1.524)
          )
          (stroke (width 0.3048) (type default))
          (fill (type none))
        )
        (polyline
          (pts
            (xy 3.048 -1.524)
            (xy 3.048 1.524)
          )
          (stroke (width 0.3302) (type default))
          (fill (type none))
        )
      )
      (symbol "C_100n_0402_1_1"
        (pin passive line (at 0 0 0) (length 2.032)
          (name "~" (effects (font (size 1.27 1.27))))
          (number "1" (effects (font (size 1.27 1.27))))
        )
        (pin passive line (at 5.08 0 180) (length 2.032)
          (name "~" (effects (font (size 1.27 1.27))))
          (number "2" (effects (font (size 1.27 1.27))))
        )
      )
    )
	(symbol "antmicroCapacitors0402:C_10p_0402" (pin_numbers hide) (pin_names hide) (in_bom yes) (on_board yes)
      (property "Reference" "C" (at 20.32 -5.08 0)
        (effects (font (size 1.27 1.27) (thickness 0.15)) (justify left bottom))
      )
      (property "Value" "C_10p_0402" (at 20.32 -10.16 0)
        (effects (font (size 1.27 1.27) (thickness 0.15)) (justify left bottom) hide)
      )
      (property "Footprint" "antmicro-footprints:C_0402_1005Metric" (at 20.32 -12.7 0)
        (effects (font (size 1.27 1.27) (thickness 0.15)) (justify left bottom) hide)
      )
      (property "Datasheet" "https://www.murata.com/products/productdetail?partno=GCM1555C1H100GA16%23" (at 20.32 -15.24 0)
        (effects (font (size 1.27 1.27) (thickness 0.15)) (justify left bottom) hide)
      )
      (property "MPN" "GCM1555C1H100GA16D" (at 20.32 -17.78 0)
        (effects (font (size 1.27 1.27) (thickness 0.15)) (justify left bottom) hide)
      )
      (property "Manufacturer" "Murata" (at 20.32 -20.32 0)
        (effects (font (size 1.27 1.27) (thickness 0.15)) (justify left bottom) hide)
      )
      (property "License" "Apache-2.0" (at 20.32 -22.86 0)
        (effects (font (size 1.27 1.27) (thickness 0.15)) (justify left bottom) hide)
      )
      (property "Author" "Antmicro" (at 20.32 -25.4 0)
        (effects (font (size 1.27 1.27) (thickness 0.15)) (justify left bottom) hide)
      )
      (property "Val" "10p" (at 20.32 -7.62 0)
        (effects (font (size 1.27 1.27) (thickness 0.15)) (justify left bottom))
      )
      (property "Voltage" "50V" (at 20.32 -27.94 0)
        (effects (font (size 1.27 1.27)) (justify left bottom) hide)
      )
      (property "Dielectric" "C0G" (at 20.32 -30.48 0)
        (effects (font (size 1.27 1.27)) (justify left bottom) hide)
      )
      (property "ki_keywords" "0402, SMT, CAPACITOR, PASSIVE" (at 0 0 0)
        (effects (font (size 1.27 1.27)) hide)
      )
      (property "ki_description" "SMD Multilayer Ceramic Capacitor, 10 pF, 50 V, 0402 [1005 Metric], ± 2%, C0G / NP0, GCM" (at 0 0 0)
        (effects (font (size 1.27 1.27)) hide)
      )
      (symbol "C_10p_0402_0_1"
        (polyline
          (pts
            (xy 2.032 -1.524)
            (xy 2.032 1.524)
          )
          (stroke (width 0.3048) (type default))
          (fill (type none))
        )
        (polyline
          (pts
            (xy 3.048 -1.524)
            (xy 3.048 1.524)
          )
          (stroke (width 0.3302) (type default))
          (fill (type none))
        )
      )
      (symbol "C_10p_0402_1_1"
        (pin passive line (at 0 0 0) (length 2.032)
          (name "~" (effects (font (size 1.27 1.27))))
          (number "1" (effects (font (size 1.27 1.27))))
        )
        (pin passive line (at 5.08 0 180) (length 2.032)
          (name "~" (effects (font (size 1.27 1.27))))
          (number "2" (effects (font (size 1.27 1.27))))
        )
      )
    )
	(symbol "antmicroCapacitors0402:C_10u_0402" (pin_numbers hide) (pin_names hide) (in_bom yes) (on_board yes)
      (property "Reference" "C" (at 20.32 -5.08 0)
        (effects (font (size 1.27 1.27) (thickness 0.15)) (justify left bottom))
      )
      (property "Value" "C_10u_0402" (at 20.32 -10.16 0)
        (effects (font (size 1.27 1.27) (thickness 0.15)) (justify left bottom) hide)
      )
      (property "Footprint" "antmicro-footprints:C_0402_1005Metric" (at 20.32 -12.7 0)
        (effects (font (size 1.27 1.27) (thickness 0.15)) (justify left bottom) hide)
      )
      (property "Datasheet" "https://www.yageo.com/en/Chart/Download/pdf/CC0402MRX5R5BB106" (at 20.32 -15.24 0)
        (effects (font (size 1.27 1.27) (thickness 0.15)) (justify left bottom) hide)
      )
      (property "MPN" "CC0402MRX5R5BB106" (at 20.32 -17.78 0)
        (effects (font (size 1.27 1.27) (thickness 0.15)) (justify left bottom) hide)
      )
      (property "Manufacturer" "YAGEO" (at 20.32 -20.32 0)
        (effects (font (size 1.27 1.27) (thickness 0.15)) (justify left bottom) hide)
      )
      (property "License" "Apache-2.0" (at 20.32 -22.86 0)
        (effects (font (size 1.27 1.27) (thickness 0.15)) (justify left bottom) hide)
      )
      (property "Author" "Antmicro" (at 20.32 -25.4 0)
        (effects (font (size 1.27 1.27) (thickness 0.15)) (justify left bottom) hide)
      )
      (property "Val" "10u" (at 20.32 -7.62 0)
        (effects (font (size 1.27 1.27) (thickness 0.15)) (justify left bottom))
      )
      (property "Voltage" "" (at 20.32 -27.94 0)
        (effects (font (size 1.27 1.27)) (justify left bottom) hide)
      )
      (property "Dielectric" "" (at 20.32 -30.48 0)
        (effects (font (size 1.27 1.27)) (justify left bottom) hide)
      )
      (property "ki_keywords" "0402, SMT, CAPACITOR, PASSIVE, MLCC, CERAMIC" (at 0 0 0)
        (effects (font (size 1.27 1.27)) hide)
      )
      (property "ki_description" "SMD Multilayer Ceramic Capacitor, 10 µF, 6.3 V, 0402 [1005 Metric], ± 20%, X5R, CC Series" (at 0 0 0)
        (effects (font (size 1.27 1.27)) hide)
      )
      (symbol "C_10u_0402_0_1"
        (polyline
          (pts
            (xy 2.032 -1.524)
            (xy 2.032 1.524)
          )
          (stroke (width 0.3048) (type default))
          (fill (type none))
        )
        (polyline
          (pts
            (xy 3.048 -1.524)
            (xy 3.048 1.524)
          )
          (stroke (width 0.3302) (type default))
          (fill (type none))
        )
      )
      (symbol "C_10u_0402_1_1"
        (pin passive line (at 0 0 0) (length 2.032)
          (name "~" (effects (font (size 1.27 1.27))))
          (number "1" (effects (font (size 1.27 1.27))))
        )
        (pin passive line (at 5.08 0 180) (length 2.032)
          (name "~" (effects (font (size 1.27 1.27))))
          (number "2" (effects (font (size 1.27 1.27))))
        )
      )
    )
	(symbol "antmicroCapacitors0402:C_1u_0402" (pin_numbers hide) (pin_names hide) (in_bom yes) (on_board yes)
      (property "Reference" "C" (at 20.32 -5.08 0)
        (effects (font (size 1.27 1.27) (thickness 0.15)) (justify left bottom))
      )
      (property "Value" "C_1u_0402" (at 20.32 -10.16 0)
        (effects (font (size 1.27 1.27) (thickness 0.15)) (justify left bottom) hide)
      )
      (property "Footprint" "antmicro-footprints:C_0402_1005Metric" (at 20.32 -12.7 0)
        (effects (font (size 1.27 1.27) (thickness 0.15)) (justify left bottom) hide)
      )
      (property "Datasheet" "https://product.tdk.com/en/search/capacitor/ceramic/mlcc/info?part_no=C1005X6S1A105K050BC" (at 20.32 -15.24 0)
        (effects (font (size 1.27 1.27) (thickness 0.15)) (justify left bottom) hide)
      )
      (property "MPN" "C1005X6S1A105K050BC" (at 20.32 -17.78 0)
        (effects (font (size 1.27 1.27) (thickness 0.15)) (justify left bottom) hide)
      )
      (property "Manufacturer" "TDK" (at 20.32 -20.32 0)
        (effects (font (size 1.27 1.27) (thickness 0.15)) (justify left bottom) hide)
      )
      (property "License" "Apache-2.0" (at 20.32 -22.86 0)
        (effects (font (size 1.27 1.27) (thickness 0.15)) (justify left bottom) hide)
      )
      (property "Author" "Antmicro" (at 20.32 -25.4 0)
        (effects (font (size 1.27 1.27) (thickness 0.15)) (justify left bottom) hide)
      )
      (property "Val" "1u" (at 20.32 -7.62 0)
        (effects (font (size 1.27 1.27) (thickness 0.15)) (justify left bottom))
      )
      (property "Voltage" "" (at 20.32 -27.94 0)
        (effects (font (size 1.27 1.27)) (justify left bottom) hide)
      )
      (property "Dielectric" "" (at 20.32 -30.48 0)
        (effects (font (size 1.27 1.27)) (justify left bottom) hide)
      )
      (property "ki_keywords" "0402, SMT, CAPACITOR, PASSIVE, CERAMIC, MLCC" (at 0 0 0)
        (effects (font (size 1.27 1.27)) hide)
      )
      (property "ki_description" "SMD Multilayer Ceramic Capacitor, 1 µF, 10 V, 0402 [1005 Metric], ± 10%, X6S, C" (at 0 0 0)
        (effects (font (size 1.27 1.27)) hide)
      )
      (symbol "C_1u_0402_0_1"
        (polyline
          (pts
            (xy 2.032 -1.524)
            (xy 2.032 1.524)
          )
          (stroke (width 0.3048) (type default))
          (fill (type none))
        )
        (polyline
          (pts
            (xy 3.048 -1.524)
            (xy 3.048 1.524)
          )
          (stroke (width 0.3302) (type default))
          (fill (type none))
        )
      )
      (symbol "C_1u_0402_1_1"
        (pin passive line (at 0 0 0) (length 2.032)
          (name "~" (effects (font (size 1.27 1.27))))
          (number "1" (effects (font (size 1.27 1.27))))
        )
        (pin passive line (at 5.08 0 180) (length 2.032)
          (name "~" (effects (font (size 1.27 1.27))))
          (number "2" (effects (font (size 1.27 1.27))))
        )
      )
    )
	(symbol "antmicroCapacitors0402:C_1u_0402_10" (pin_numbers hide) (pin_names hide) (in_bom yes) (on_board yes)
      (property "Reference" "C" (at 20.32 -5.08 0)
        (effects (font (size 1.27 1.27) (thickness 0.15)) (justify left bottom))
      )
      (property "Value" "C_1u_0402_10" (at 20.32 -10.16 0)
        (effects (font (size 1.27 1.27) (thickness 0.15)) (justify left bottom) hide)
      )
      (property "Footprint" "antmicro-footprints:C_0402_1005Metric" (at 20.32 -12.7 0)
        (effects (font (size 1.27 1.27) (thickness 0.15)) (justify left bottom) hide)
      )
      (property "Datasheet" " " (at 20.32 -15.24 0)
        (effects (font (size 1.27 1.27) (thickness 0.15)) (justify left bottom) hide)
      )
      (property "MPN" "C1005X6S1A105K050BC" (at 20.32 -17.78 0)
        (effects (font (size 1.27 1.27) (thickness 0.15)) (justify left bottom) hide)
      )
      (property "Manufacturer" "TDK" (at 20.32 -20.32 0)
        (effects (font (size 1.27 1.27) (thickness 0.15)) (justify left bottom) hide)
      )
      (property "License" "Apache-2.0" (at 20.32 -22.86 0)
        (effects (font (size 1.27 1.27) (thickness 0.15)) (justify left bottom) hide)
      )
      (property "Author" "Antmicro" (at 20.32 -25.4 0)
        (effects (font (size 1.27 1.27) (thickness 0.15)) (justify left bottom) hide)
      )
      (property "Val" "1u" (at 20.32 -7.62 0)
        (effects (font (size 1.27 1.27) (thickness 0.15)) (justify left bottom))
      )
      (property "Voltage" "" (at 20.32 -27.94 0)
        (effects (font (size 1.27 1.27)) (justify left bottom) hide)
      )
      (property "Dielectric" "" (at 20.32 -30.48 0)
        (effects (font (size 1.27 1.27)) (justify left bottom) hide)
      )
      (property "ki_description" " " (at 0 0 0)
        (effects (font (size 1.27 1.27)) hide)
      )
      (symbol "C_1u_0402_10_0_1"
        (polyline
          (pts
            (xy 2.032 -1.524)
            (xy 2.032 1.524)
          )
          (stroke (width 0.3048) (type default))
          (fill (type none))
        )
        (polyline
          (pts
            (xy 3.048 -1.524)
            (xy 3.048 1.524)
          )
          (stroke (width 0.3302) (type default))
          (fill (type none))
        )
      )
      (symbol "C_1u_0402_10_1_1"
        (pin passive line (at 0 0 0) (length 2.032)
          (name "~" (effects (font (size 1.27 1.27))))
          (number "1" (effects (font (size 1.27 1.27))))
        )
        (pin passive line (at 5.08 0 180) (length 2.032)
          (name "~" (effects (font (size 1.27 1.27))))
          (number "2" (effects (font (size 1.27 1.27))))
        )
      )
    )
	(symbol "antmicroCapacitors0402:C_1u_0402_11" (pin_numbers hide) (pin_names hide) (in_bom yes) (on_board yes)
      (property "Reference" "C" (at 20.32 -5.08 0)
        (effects (font (size 1.27 1.27) (thickness 0.15)) (justify left bottom))
      )
      (property "Value" "C_1u_0402_11" (at 20.32 -10.16 0)
        (effects (font (size 1.27 1.27) (thickness 0.15)) (justify left bottom) hide)
      )
      (property "Footprint" "antmicro-footprints:C_0402_1005Metric" (at 20.32 -12.7 0)
        (effects (font (size 1.27 1.27) (thickness 0.15)) (justify left bottom) hide)
      )
      (property "Datasheet" " " (at 20.32 -15.24 0)
        (effects (font (size 1.27 1.27) (thickness 0.15)) (justify left bottom) hide)
      )
      (property "MPN" "C1005X6S1A105K050BC" (at 20.32 -17.78 0)
        (effects (font (size 1.27 1.27) (thickness 0.15)) (justify left bottom) hide)
      )
      (property "Manufacturer" "TDK" (at 20.32 -20.32 0)
        (effects (font (size 1.27 1.27) (thickness 0.15)) (justify left bottom) hide)
      )
      (property "License" "Apache-2.0" (at 20.32 -22.86 0)
        (effects (font (size 1.27 1.27) (thickness 0.15)) (justify left bottom) hide)
      )
      (property "Author" "Antmicro" (at 20.32 -25.4 0)
        (effects (font (size 1.27 1.27) (thickness 0.15)) (justify left bottom) hide)
      )
      (property "Val" "1u" (at 20.32 -7.62 0)
        (effects (font (size 1.27 1.27) (thickness 0.15)) (justify left bottom))
      )
      (property "Voltage" "" (at 20.32 -27.94 0)
        (effects (font (size 1.27 1.27)) (justify left bottom) hide)
      )
      (property "Dielectric" "" (at 20.32 -30.48 0)
        (effects (font (size 1.27 1.27)) (justify left bottom) hide)
      )
      (property "ki_description" " " (at 0 0 0)
        (effects (font (size 1.27 1.27)) hide)
      )
      (symbol "C_1u_0402_11_0_1"
        (polyline
          (pts
            (xy 2.032 -1.524)
            (xy 2.032 1.524)
          )
          (stroke (width 0.3048) (type default))
          (fill (type none))
        )
        (polyline
          (pts
            (xy 3.048 -1.524)
            (xy 3.048 1.524)
          )
          (stroke (width 0.3302) (type default))
          (fill (type none))
        )
      )
      (symbol "C_1u_0402_11_1_1"
        (pin passive line (at 0 0 0) (length 2.032)
          (name "~" (effects (font (size 1.27 1.27))))
          (number "1" (effects (font (size 1.27 1.27))))
        )
        (pin passive line (at 5.08 0 180) (length 2.032)
          (name "~" (effects (font (size 1.27 1.27))))
          (number "2" (effects (font (size 1.27 1.27))))
        )
      )
    )
	(symbol "antmicroCapacitors0402:C_1u_0402_12" (pin_numbers hide) (pin_names hide) (in_bom yes) (on_board yes)
      (property "Reference" "C" (at 20.32 -5.08 0)
        (effects (font (size 1.27 1.27) (thickness 0.15)) (justify left bottom))
      )
      (property "Value" "C_1u_0402_12" (at 20.32 -10.16 0)
        (effects (font (size 1.27 1.27) (thickness 0.15)) (justify left bottom) hide)
      )
      (property "Footprint" "antmicro-footprints:C_0402_1005Metric" (at 20.32 -12.7 0)
        (effects (font (size 1.27 1.27) (thickness 0.15)) (justify left bottom) hide)
      )
      (property "Datasheet" " " (at 20.32 -15.24 0)
        (effects (font (size 1.27 1.27) (thickness 0.15)) (justify left bottom) hide)
      )
      (property "MPN" "C1005X6S1A105K050BC" (at 20.32 -17.78 0)
        (effects (font (size 1.27 1.27) (thickness 0.15)) (justify left bottom) hide)
      )
      (property "Manufacturer" "TDK" (at 20.32 -20.32 0)
        (effects (font (size 1.27 1.27) (thickness 0.15)) (justify left bottom) hide)
      )
      (property "License" "Apache-2.0" (at 20.32 -22.86 0)
        (effects (font (size 1.27 1.27) (thickness 0.15)) (justify left bottom) hide)
      )
      (property "Author" "Antmicro" (at 20.32 -25.4 0)
        (effects (font (size 1.27 1.27) (thickness 0.15)) (justify left bottom) hide)
      )
      (property "Val" "1u" (at 20.32 -7.62 0)
        (effects (font (size 1.27 1.27) (thickness 0.15)) (justify left bottom))
      )
      (property "Voltage" "" (at 20.32 -27.94 0)
        (effects (font (size 1.27 1.27)) (justify left bottom) hide)
      )
      (property "Dielectric" "" (at 20.32 -30.48 0)
        (effects (font (size 1.27 1.27)) (justify left bottom) hide)
      )
      (property "ki_description" " " (at 0 0 0)
        (effects (font (size 1.27 1.27)) hide)
      )
      (symbol "C_1u_0402_12_0_1"
        (polyline
          (pts
            (xy 2.032 -1.524)
            (xy 2.032 1.524)
          )
          (stroke (width 0.3048) (type default))
          (fill (type none))
        )
        (polyline
          (pts
            (xy 3.048 -1.524)
            (xy 3.048 1.524)
          )
          (stroke (width 0.3302) (type default))
          (fill (type none))
        )
      )
      (symbol "C_1u_0402_12_1_1"
        (pin passive line (at 0 0 0) (length 2.032)
          (name "~" (effects (font (size 1.27 1.27))))
          (number "1" (effects (font (size 1.27 1.27))))
        )
        (pin passive line (at 5.08 0 180) (length 2.032)
          (name "~" (effects (font (size 1.27 1.27))))
          (number "2" (effects (font (size 1.27 1.27))))
        )
      )
    )
	(symbol "antmicroCapacitors0402:C_1u_0402_13" (pin_numbers hide) (pin_names hide) (in_bom yes) (on_board yes)
      (property "Reference" "C" (at 20.32 -5.08 0)
        (effects (font (size 1.27 1.27) (thickness 0.15)) (justify left bottom))
      )
      (property "Value" "C_1u_0402_13" (at 20.32 -10.16 0)
        (effects (font (size 1.27 1.27) (thickness 0.15)) (justify left bottom) hide)
      )
      (property "Footprint" "antmicro-footprints:C_0402_1005Metric" (at 20.32 -12.7 0)
        (effects (font (size 1.27 1.27) (thickness 0.15)) (justify left bottom) hide)
      )
      (property "Datasheet" " " (at 20.32 -15.24 0)
        (effects (font (size 1.27 1.27) (thickness 0.15)) (justify left bottom) hide)
      )
      (property "MPN" "C1005X6S1A105K050BC" (at 20.32 -17.78 0)
        (effects (font (size 1.27 1.27) (thickness 0.15)) (justify left bottom) hide)
      )
      (property "Manufacturer" "TDK" (at 20.32 -20.32 0)
        (effects (font (size 1.27 1.27) (thickness 0.15)) (justify left bottom) hide)
      )
      (property "License" "Apache-2.0" (at 20.32 -22.86 0)
        (effects (font (size 1.27 1.27) (thickness 0.15)) (justify left bottom) hide)
      )
      (property "Author" "Antmicro" (at 20.32 -25.4 0)
        (effects (font (size 1.27 1.27) (thickness 0.15)) (justify left bottom) hide)
      )
      (property "Val" "1u" (at 20.32 -7.62 0)
        (effects (font (size 1.27 1.27) (thickness 0.15)) (justify left bottom))
      )
      (property "Voltage" "" (at 20.32 -27.94 0)
        (effects (font (size 1.27 1.27)) (justify left bottom) hide)
      )
      (property "Dielectric" "" (at 20.32 -30.48 0)
        (effects (font (size 1.27 1.27)) (justify left bottom) hide)
      )
      (property "ki_description" " " (at 0 0 0)
        (effects (font (size 1.27 1.27)) hide)
      )
      (symbol "C_1u_0402_13_0_1"
        (polyline
          (pts
            (xy 2.032 -1.524)
            (xy 2.032 1.524)
          )
          (stroke (width 0.3048) (type default))
          (fill (type none))
        )
        (polyline
          (pts
            (xy 3.048 -1.524)
            (xy 3.048 1.524)
          )
          (stroke (width 0.3302) (type default))
          (fill (type none))
        )
      )
      (symbol "C_1u_0402_13_1_1"
        (pin passive line (at 0 0 0) (length 2.032)
          (name "~" (effects (font (size 1.27 1.27))))
          (number "1" (effects (font (size 1.27 1.27))))
        )
        (pin passive line (at 5.08 0 180) (length 2.032)
          (name "~" (effects (font (size 1.27 1.27))))
          (number "2" (effects (font (size 1.27 1.27))))
        )
      )
    )
	(symbol "antmicroCapacitors0402:C_1u_0402_14" (pin_numbers hide) (pin_names hide) (in_bom yes) (on_board yes)
      (property "Reference" "C" (at 20.32 -5.08 0)
        (effects (font (size 1.27 1.27) (thickness 0.15)) (justify left bottom))
      )
      (property "Value" "C_1u_0402_14" (at 20.32 -10.16 0)
        (effects (font (size 1.27 1.27) (thickness 0.15)) (justify left bottom) hide)
      )
      (property "Footprint" "antmicro-footprints:C_0402_1005Metric" (at 20.32 -12.7 0)
        (effects (font (size 1.27 1.27) (thickness 0.15)) (justify left bottom) hide)
      )
      (property "Datasheet" " " (at 20.32 -15.24 0)
        (effects (font (size 1.27 1.27) (thickness 0.15)) (justify left bottom) hide)
      )
      (property "MPN" "C1005X6S1A105K050BC" (at 20.32 -17.78 0)
        (effects (font (size 1.27 1.27) (thickness 0.15)) (justify left bottom) hide)
      )
      (property "Manufacturer" "TDK" (at 20.32 -20.32 0)
        (effects (font (size 1.27 1.27) (thickness 0.15)) (justify left bottom) hide)
      )
      (property "License" "Apache-2.0" (at 20.32 -22.86 0)
        (effects (font (size 1.27 1.27) (thickness 0.15)) (justify left bottom) hide)
      )
      (property "Author" "Antmicro" (at 20.32 -25.4 0)
        (effects (font (size 1.27 1.27) (thickness 0.15)) (justify left bottom) hide)
      )
      (property "Val" "1u" (at 20.32 -7.62 0)
        (effects (font (size 1.27 1.27) (thickness 0.15)) (justify left bottom))
      )
      (property "Voltage" "" (at 20.32 -27.94 0)
        (effects (font (size 1.27 1.27)) (justify left bottom) hide)
      )
      (property "Dielectric" "" (at 20.32 -30.48 0)
        (effects (font (size 1.27 1.27)) (justify left bottom) hide)
      )
      (property "ki_description" " " (at 0 0 0)
        (effects (font (size 1.27 1.27)) hide)
      )
      (symbol "C_1u_0402_14_0_1"
        (polyline
          (pts
            (xy 2.032 -1.524)
            (xy 2.032 1.524)
          )
          (stroke (width 0.3048) (type default))
          (fill (type none))
        )
        (polyline
          (pts
            (xy 3.048 -1.524)
            (xy 3.048 1.524)
          )
          (stroke (width 0.3302) (type default))
          (fill (type none))
        )
      )
      (symbol "C_1u_0402_14_1_1"
        (pin passive line (at 0 0 0) (length 2.032)
          (name "~" (effects (font (size 1.27 1.27))))
          (number "1" (effects (font (size 1.27 1.27))))
        )
        (pin passive line (at 5.08 0 180) (length 2.032)
          (name "~" (effects (font (size 1.27 1.27))))
          (number "2" (effects (font (size 1.27 1.27))))
        )
      )
    )
	(symbol "antmicroCapacitors0402:C_1u_0402_15" (pin_numbers hide) (pin_names hide) (in_bom yes) (on_board yes)
      (property "Reference" "C" (at 20.32 -5.08 0)
        (effects (font (size 1.27 1.27) (thickness 0.15)) (justify left bottom))
      )
      (property "Value" "C_1u_0402_15" (at 20.32 -10.16 0)
        (effects (font (size 1.27 1.27) (thickness 0.15)) (justify left bottom) hide)
      )
      (property "Footprint" "antmicro-footprints:C_0402_1005Metric" (at 20.32 -12.7 0)
        (effects (font (size 1.27 1.27) (thickness 0.15)) (justify left bottom) hide)
      )
      (property "Datasheet" " " (at 20.32 -15.24 0)
        (effects (font (size 1.27 1.27) (thickness 0.15)) (justify left bottom) hide)
      )
      (property "MPN" "C1005X6S1A105K050BC" (at 20.32 -17.78 0)
        (effects (font (size 1.27 1.27) (thickness 0.15)) (justify left bottom) hide)
      )
      (property "Manufacturer" "TDK" (at 20.32 -20.32 0)
        (effects (font (size 1.27 1.27) (thickness 0.15)) (justify left bottom) hide)
      )
      (property "License" "Apache-2.0" (at 20.32 -22.86 0)
        (effects (font (size 1.27 1.27) (thickness 0.15)) (justify left bottom) hide)
      )
      (property "Author" "Antmicro" (at 20.32 -25.4 0)
        (effects (font (size 1.27 1.27) (thickness 0.15)) (justify left bottom) hide)
      )
      (property "Val" "1u" (at 20.32 -7.62 0)
        (effects (font (size 1.27 1.27) (thickness 0.15)) (justify left bottom))
      )
      (property "Voltage" "" (at 20.32 -27.94 0)
        (effects (font (size 1.27 1.27)) (justify left bottom) hide)
      )
      (property "Dielectric" "" (at 20.32 -30.48 0)
        (effects (font (size 1.27 1.27)) (justify left bottom) hide)
      )
      (property "ki_description" " " (at 0 0 0)
        (effects (font (size 1.27 1.27)) hide)
      )
      (symbol "C_1u_0402_15_0_1"
        (polyline
          (pts
            (xy 2.032 -1.524)
            (xy 2.032 1.524)
          )
          (stroke (width 0.3048) (type default))
          (fill (type none))
        )
        (polyline
          (pts
            (xy 3.048 -1.524)
            (xy 3.048 1.524)
          )
          (stroke (width 0.3302) (type default))
          (fill (type none))
        )
      )
      (symbol "C_1u_0402_15_1_1"
        (pin passive line (at 0 0 0) (length 2.032)
          (name "~" (effects (font (size 1.27 1.27))))
          (number "1" (effects (font (size 1.27 1.27))))
        )
        (pin passive line (at 5.08 0 180) (length 2.032)
          (name "~" (effects (font (size 1.27 1.27))))
          (number "2" (effects (font (size 1.27 1.27))))
        )
      )
    )
	(symbol "antmicroCapacitors0402:C_1u_0402_16" (pin_numbers hide) (pin_names hide) (in_bom yes) (on_board yes)
      (property "Reference" "C" (at 20.32 -5.08 0)
        (effects (font (size 1.27 1.27) (thickness 0.15)) (justify left bottom))
      )
      (property "Value" "C_1u_0402_16" (at 20.32 -10.16 0)
        (effects (font (size 1.27 1.27) (thickness 0.15)) (justify left bottom) hide)
      )
      (property "Footprint" "antmicro-footprints:C_0402_1005Metric" (at 20.32 -12.7 0)
        (effects (font (size 1.27 1.27) (thickness 0.15)) (justify left bottom) hide)
      )
      (property "Datasheet" " " (at 20.32 -15.24 0)
        (effects (font (size 1.27 1.27) (thickness 0.15)) (justify left bottom) hide)
      )
      (property "MPN" "C1005X6S1A105K050BC" (at 20.32 -17.78 0)
        (effects (font (size 1.27 1.27) (thickness 0.15)) (justify left bottom) hide)
      )
      (property "Manufacturer" "TDK" (at 20.32 -20.32 0)
        (effects (font (size 1.27 1.27) (thickness 0.15)) (justify left bottom) hide)
      )
      (property "License" "Apache-2.0" (at 20.32 -22.86 0)
        (effects (font (size 1.27 1.27) (thickness 0.15)) (justify left bottom) hide)
      )
      (property "Author" "Antmicro" (at 20.32 -25.4 0)
        (effects (font (size 1.27 1.27) (thickness 0.15)) (justify left bottom) hide)
      )
      (property "Val" "1u" (at 20.32 -7.62 0)
        (effects (font (size 1.27 1.27) (thickness 0.15)) (justify left bottom))
      )
      (property "Voltage" "" (at 20.32 -27.94 0)
        (effects (font (size 1.27 1.27)) (justify left bottom) hide)
      )
      (property "Dielectric" "" (at 20.32 -30.48 0)
        (effects (font (size 1.27 1.27)) (justify left bottom) hide)
      )
      (property "ki_description" " " (at 0 0 0)
        (effects (font (size 1.27 1.27)) hide)
      )
      (symbol "C_1u_0402_16_0_1"
        (polyline
          (pts
            (xy 2.032 -1.524)
            (xy 2.032 1.524)
          )
          (stroke (width 0.3048) (type default))
          (fill (type none))
        )
        (polyline
          (pts
            (xy 3.048 -1.524)
            (xy 3.048 1.524)
          )
          (stroke (width 0.3302) (type default))
          (fill (type none))
        )
      )
      (symbol "C_1u_0402_16_1_1"
        (pin passive line (at 0 0 0) (length 2.032)
          (name "~" (effects (font (size 1.27 1.27))))
          (number "1" (effects (font (size 1.27 1.27))))
        )
        (pin passive line (at 5.08 0 180) (length 2.032)
          (name "~" (effects (font (size 1.27 1.27))))
          (number "2" (effects (font (size 1.27 1.27))))
        )
      )
    )
	(symbol "antmicroCapacitors0402:C_1u_0402_17" (pin_numbers hide) (pin_names hide) (in_bom yes) (on_board yes)
      (property "Reference" "C" (at 20.32 -5.08 0)
        (effects (font (size 1.27 1.27) (thickness 0.15)) (justify left bottom))
      )
      (property "Value" "C_1u_0402_17" (at 20.32 -10.16 0)
        (effects (font (size 1.27 1.27) (thickness 0.15)) (justify left bottom) hide)
      )
      (property "Footprint" "antmicro-footprints:C_0402_1005Metric" (at 20.32 -12.7 0)
        (effects (font (size 1.27 1.27) (thickness 0.15)) (justify left bottom) hide)
      )
      (property "Datasheet" " " (at 20.32 -15.24 0)
        (effects (font (size 1.27 1.27) (thickness 0.15)) (justify left bottom) hide)
      )
      (property "MPN" "C1005X6S1A105K050BC" (at 20.32 -17.78 0)
        (effects (font (size 1.27 1.27) (thickness 0.15)) (justify left bottom) hide)
      )
      (property "Manufacturer" "TDK" (at 20.32 -20.32 0)
        (effects (font (size 1.27 1.27) (thickness 0.15)) (justify left bottom) hide)
      )
      (property "License" "Apache-2.0" (at 20.32 -22.86 0)
        (effects (font (size 1.27 1.27) (thickness 0.15)) (justify left bottom) hide)
      )
      (property "Author" "Antmicro" (at 20.32 -25.4 0)
        (effects (font (size 1.27 1.27) (thickness 0.15)) (justify left bottom) hide)
      )
      (property "Val" "1u" (at 20.32 -7.62 0)
        (effects (font (size 1.27 1.27) (thickness 0.15)) (justify left bottom))
      )
      (property "Voltage" "" (at 20.32 -27.94 0)
        (effects (font (size 1.27 1.27)) (justify left bottom) hide)
      )
      (property "Dielectric" "" (at 20.32 -30.48 0)
        (effects (font (size 1.27 1.27)) (justify left bottom) hide)
      )
      (property "ki_description" " " (at 0 0 0)
        (effects (font (size 1.27 1.27)) hide)
      )
      (symbol "C_1u_0402_17_0_1"
        (polyline
          (pts
            (xy 2.032 -1.524)
            (xy 2.032 1.524)
          )
          (stroke (width 0.3048) (type default))
          (fill (type none))
        )
        (polyline
          (pts
            (xy 3.048 -1.524)
            (xy 3.048 1.524)
          )
          (stroke (width 0.3302) (type default))
          (fill (type none))
        )
      )
      (symbol "C_1u_0402_17_1_1"
        (pin passive line (at 0 0 0) (length 2.032)
          (name "~" (effects (font (size 1.27 1.27))))
          (number "1" (effects (font (size 1.27 1.27))))
        )
        (pin passive line (at 5.08 0 180) (length 2.032)
          (name "~" (effects (font (size 1.27 1.27))))
          (number "2" (effects (font (size 1.27 1.27))))
        )
      )
    )
	(symbol "antmicroCapacitors0402:C_1u_0402_18" (pin_numbers hide) (pin_names hide) (in_bom yes) (on_board yes)
      (property "Reference" "C" (at 20.32 -5.08 0)
        (effects (font (size 1.27 1.27) (thickness 0.15)) (justify left bottom))
      )
      (property "Value" "C_1u_0402_18" (at 20.32 -10.16 0)
        (effects (font (size 1.27 1.27) (thickness 0.15)) (justify left bottom) hide)
      )
      (property "Footprint" "antmicro-footprints:C_0402_1005Metric" (at 20.32 -12.7 0)
        (effects (font (size 1.27 1.27) (thickness 0.15)) (justify left bottom) hide)
      )
      (property "Datasheet" " " (at 20.32 -15.24 0)
        (effects (font (size 1.27 1.27) (thickness 0.15)) (justify left bottom) hide)
      )
      (property "MPN" "C1005X6S1A105K050BC" (at 20.32 -17.78 0)
        (effects (font (size 1.27 1.27) (thickness 0.15)) (justify left bottom) hide)
      )
      (property "Manufacturer" "TDK" (at 20.32 -20.32 0)
        (effects (font (size 1.27 1.27) (thickness 0.15)) (justify left bottom) hide)
      )
      (property "License" "Apache-2.0" (at 20.32 -22.86 0)
        (effects (font (size 1.27 1.27) (thickness 0.15)) (justify left bottom) hide)
      )
      (property "Author" "Antmicro" (at 20.32 -25.4 0)
        (effects (font (size 1.27 1.27) (thickness 0.15)) (justify left bottom) hide)
      )
      (property "Val" "1u" (at 20.32 -7.62 0)
        (effects (font (size 1.27 1.27) (thickness 0.15)) (justify left bottom))
      )
      (property "Voltage" "" (at 20.32 -27.94 0)
        (effects (font (size 1.27 1.27)) (justify left bottom) hide)
      )
      (property "Dielectric" "" (at 20.32 -30.48 0)
        (effects (font (size 1.27 1.27)) (justify left bottom) hide)
      )
      (property "ki_description" " " (at 0 0 0)
        (effects (font (size 1.27 1.27)) hide)
      )
      (symbol "C_1u_0402_18_0_1"
        (polyline
          (pts
            (xy 2.032 -1.524)
            (xy 2.032 1.524)
          )
          (stroke (width 0.3048) (type default))
          (fill (type none))
        )
        (polyline
          (pts
            (xy 3.048 -1.524)
            (xy 3.048 1.524)
          )
          (stroke (width 0.3302) (type default))
          (fill (type none))
        )
      )
      (symbol "C_1u_0402_18_1_1"
        (pin passive line (at 0 0 0) (length 2.032)
          (name "~" (effects (font (size 1.27 1.27))))
          (number "1" (effects (font (size 1.27 1.27))))
        )
        (pin passive line (at 5.08 0 180) (length 2.032)
          (name "~" (effects (font (size 1.27 1.27))))
          (number "2" (effects (font (size 1.27 1.27))))
        )
      )
    )
	(symbol "antmicroCapacitors0402:C_1u_0402_19" (pin_numbers hide) (pin_names hide) (in_bom yes) (on_board yes)
      (property "Reference" "C" (at 20.32 -5.08 0)
        (effects (font (size 1.27 1.27) (thickness 0.15)) (justify left bottom))
      )
      (property "Value" "C_1u_0402_19" (at 20.32 -10.16 0)
        (effects (font (size 1.27 1.27) (thickness 0.15)) (justify left bottom) hide)
      )
      (property "Footprint" "antmicro-footprints:C_0402_1005Metric" (at 20.32 -12.7 0)
        (effects (font (size 1.27 1.27) (thickness 0.15)) (justify left bottom) hide)
      )
      (property "Datasheet" " " (at 20.32 -15.24 0)
        (effects (font (size 1.27 1.27) (thickness 0.15)) (justify left bottom) hide)
      )
      (property "MPN" "C1005X6S1A105K050BC" (at 20.32 -17.78 0)
        (effects (font (size 1.27 1.27) (thickness 0.15)) (justify left bottom) hide)
      )
      (property "Manufacturer" "TDK" (at 20.32 -20.32 0)
        (effects (font (size 1.27 1.27) (thickness 0.15)) (justify left bottom) hide)
      )
      (property "License" "Apache-2.0" (at 20.32 -22.86 0)
        (effects (font (size 1.27 1.27) (thickness 0.15)) (justify left bottom) hide)
      )
      (property "Author" "Antmicro" (at 20.32 -25.4 0)
        (effects (font (size 1.27 1.27) (thickness 0.15)) (justify left bottom) hide)
      )
      (property "Val" "1u" (at 20.32 -7.62 0)
        (effects (font (size 1.27 1.27) (thickness 0.15)) (justify left bottom))
      )
      (property "Voltage" "" (at 20.32 -27.94 0)
        (effects (font (size 1.27 1.27)) (justify left bottom) hide)
      )
      (property "Dielectric" "" (at 20.32 -30.48 0)
        (effects (font (size 1.27 1.27)) (justify left bottom) hide)
      )
      (property "ki_description" " " (at 0 0 0)
        (effects (font (size 1.27 1.27)) hide)
      )
      (symbol "C_1u_0402_19_0_1"
        (polyline
          (pts
            (xy 2.032 -1.524)
            (xy 2.032 1.524)
          )
          (stroke (width 0.3048) (type default))
          (fill (type none))
        )
        (polyline
          (pts
            (xy 3.048 -1.524)
            (xy 3.048 1.524)
          )
          (stroke (width 0.3302) (type default))
          (fill (type none))
        )
      )
      (symbol "C_1u_0402_19_1_1"
        (pin passive line (at 0 0 0) (length 2.032)
          (name "~" (effects (font (size 1.27 1.27))))
          (number "1" (effects (font (size 1.27 1.27))))
        )
        (pin passive line (at 5.08 0 180) (length 2.032)
          (name "~" (effects (font (size 1.27 1.27))))
          (number "2" (effects (font (size 1.27 1.27))))
        )
      )
    )
	(symbol "antmicroCapacitors0402:C_1u_0402_20" (pin_numbers hide) (pin_names hide) (in_bom yes) (on_board yes)
      (property "Reference" "C" (at 20.32 -5.08 0)
        (effects (font (size 1.27 1.27) (thickness 0.15)) (justify left bottom))
      )
      (property "Value" "C_1u_0402_20" (at 20.32 -10.16 0)
        (effects (font (size 1.27 1.27) (thickness 0.15)) (justify left bottom) hide)
      )
      (property "Footprint" "antmicro-footprints:C_0402_1005Metric" (at 20.32 -12.7 0)
        (effects (font (size 1.27 1.27) (thickness 0.15)) (justify left bottom) hide)
      )
      (property "Datasheet" " " (at 20.32 -15.24 0)
        (effects (font (size 1.27 1.27) (thickness 0.15)) (justify left bottom) hide)
      )
      (property "MPN" "C1005X6S1A105K050BC" (at 20.32 -17.78 0)
        (effects (font (size 1.27 1.27) (thickness 0.15)) (justify left bottom) hide)
      )
      (property "Manufacturer" "TDK" (at 20.32 -20.32 0)
        (effects (font (size 1.27 1.27) (thickness 0.15)) (justify left bottom) hide)
      )
      (property "License" "Apache-2.0" (at 20.32 -22.86 0)
        (effects (font (size 1.27 1.27) (thickness 0.15)) (justify left bottom) hide)
      )
      (property "Author" "Antmicro" (at 20.32 -25.4 0)
        (effects (font (size 1.27 1.27) (thickness 0.15)) (justify left bottom) hide)
      )
      (property "Val" "1u" (at 20.32 -7.62 0)
        (effects (font (size 1.27 1.27) (thickness 0.15)) (justify left bottom))
      )
      (property "Voltage" "" (at 20.32 -27.94 0)
        (effects (font (size 1.27 1.27)) (justify left bottom) hide)
      )
      (property "Dielectric" "" (at 20.32 -30.48 0)
        (effects (font (size 1.27 1.27)) (justify left bottom) hide)
      )
      (property "ki_description" " " (at 0 0 0)
        (effects (font (size 1.27 1.27)) hide)
      )
      (symbol "C_1u_0402_20_0_1"
        (polyline
          (pts
            (xy 2.032 -1.524)
            (xy 2.032 1.524)
          )
          (stroke (width 0.3048) (type default))
          (fill (type none))
        )
        (polyline
          (pts
            (xy 3.048 -1.524)
            (xy 3.048 1.524)
          )
          (stroke (width 0.3302) (type default))
          (fill (type none))
        )
      )
      (symbol "C_1u_0402_20_1_1"
        (pin passive line (at 0 0 0) (length 2.032)
          (name "~" (effects (font (size 1.27 1.27))))
          (number "1" (effects (font (size 1.27 1.27))))
        )
        (pin passive line (at 5.08 0 180) (length 2.032)
          (name "~" (effects (font (size 1.27 1.27))))
          (number "2" (effects (font (size 1.27 1.27))))
        )
      )
    )
	(symbol "antmicroCapacitors0402:C_1u_0402_21" (pin_numbers hide) (pin_names hide) (in_bom yes) (on_board yes)
      (property "Reference" "C" (at 20.32 -5.08 0)
        (effects (font (size 1.27 1.27) (thickness 0.15)) (justify left bottom))
      )
      (property "Value" "C_1u_0402_21" (at 20.32 -10.16 0)
        (effects (font (size 1.27 1.27) (thickness 0.15)) (justify left bottom) hide)
      )
      (property "Footprint" "antmicro-footprints:C_0402_1005Metric" (at 20.32 -12.7 0)
        (effects (font (size 1.27 1.27) (thickness 0.15)) (justify left bottom) hide)
      )
      (property "Datasheet" " " (at 20.32 -15.24 0)
        (effects (font (size 1.27 1.27) (thickness 0.15)) (justify left bottom) hide)
      )
      (property "MPN" "C1005X6S1A105K050BC" (at 20.32 -17.78 0)
        (effects (font (size 1.27 1.27) (thickness 0.15)) (justify left bottom) hide)
      )
      (property "Manufacturer" "TDK" (at 20.32 -20.32 0)
        (effects (font (size 1.27 1.27) (thickness 0.15)) (justify left bottom) hide)
      )
      (property "License" "Apache-2.0" (at 20.32 -22.86 0)
        (effects (font (size 1.27 1.27) (thickness 0.15)) (justify left bottom) hide)
      )
      (property "Author" "Antmicro" (at 20.32 -25.4 0)
        (effects (font (size 1.27 1.27) (thickness 0.15)) (justify left bottom) hide)
      )
      (property "Val" "1u" (at 20.32 -7.62 0)
        (effects (font (size 1.27 1.27) (thickness 0.15)) (justify left bottom))
      )
      (property "Voltage" "" (at 20.32 -27.94 0)
        (effects (font (size 1.27 1.27)) (justify left bottom) hide)
      )
      (property "Dielectric" "" (at 20.32 -30.48 0)
        (effects (font (size 1.27 1.27)) (justify left bottom) hide)
      )
      (property "ki_description" " " (at 0 0 0)
        (effects (font (size 1.27 1.27)) hide)
      )
      (symbol "C_1u_0402_21_0_1"
        (polyline
          (pts
            (xy 2.032 -1.524)
            (xy 2.032 1.524)
          )
          (stroke (width 0.3048) (type default))
          (fill (type none))
        )
        (polyline
          (pts
            (xy 3.048 -1.524)
            (xy 3.048 1.524)
          )
          (stroke (width 0.3302) (type default))
          (fill (type none))
        )
      )
      (symbol "C_1u_0402_21_1_1"
        (pin passive line (at 0 0 0) (length 2.032)
          (name "~" (effects (font (size 1.27 1.27))))
          (number "1" (effects (font (size 1.27 1.27))))
        )
        (pin passive line (at 5.08 0 180) (length 2.032)
          (name "~" (effects (font (size 1.27 1.27))))
          (number "2" (effects (font (size 1.27 1.27))))
        )
      )
    )
	(symbol "antmicroCapacitors0402:C_1u_0402_22" (pin_numbers hide) (pin_names hide) (in_bom yes) (on_board yes)
      (property "Reference" "C" (at 20.32 -5.08 0)
        (effects (font (size 1.27 1.27) (thickness 0.15)) (justify left bottom))
      )
      (property "Value" "C_1u_0402_22" (at 20.32 -10.16 0)
        (effects (font (size 1.27 1.27) (thickness 0.15)) (justify left bottom) hide)
      )
      (property "Footprint" "antmicro-footprints:C_0402_1005Metric" (at 20.32 -12.7 0)
        (effects (font (size 1.27 1.27) (thickness 0.15)) (justify left bottom) hide)
      )
      (property "Datasheet" " " (at 20.32 -15.24 0)
        (effects (font (size 1.27 1.27) (thickness 0.15)) (justify left bottom) hide)
      )
      (property "MPN" "C1005X6S1A105K050BC" (at 20.32 -17.78 0)
        (effects (font (size 1.27 1.27) (thickness 0.15)) (justify left bottom) hide)
      )
      (property "Manufacturer" "TDK" (at 20.32 -20.32 0)
        (effects (font (size 1.27 1.27) (thickness 0.15)) (justify left bottom) hide)
      )
      (property "License" "Apache-2.0" (at 20.32 -22.86 0)
        (effects (font (size 1.27 1.27) (thickness 0.15)) (justify left bottom) hide)
      )
      (property "Author" "Antmicro" (at 20.32 -25.4 0)
        (effects (font (size 1.27 1.27) (thickness 0.15)) (justify left bottom) hide)
      )
      (property "Val" "1u" (at 20.32 -7.62 0)
        (effects (font (size 1.27 1.27) (thickness 0.15)) (justify left bottom))
      )
      (property "Voltage" "" (at 20.32 -27.94 0)
        (effects (font (size 1.27 1.27)) (justify left bottom) hide)
      )
      (property "Dielectric" "" (at 20.32 -30.48 0)
        (effects (font (size 1.27 1.27)) (justify left bottom) hide)
      )
      (property "ki_description" " " (at 0 0 0)
        (effects (font (size 1.27 1.27)) hide)
      )
      (symbol "C_1u_0402_22_0_1"
        (polyline
          (pts
            (xy 2.032 -1.524)
            (xy 2.032 1.524)
          )
          (stroke (width 0.3048) (type default))
          (fill (type none))
        )
        (polyline
          (pts
            (xy 3.048 -1.524)
            (xy 3.048 1.524)
          )
          (stroke (width 0.3302) (type default))
          (fill (type none))
        )
      )
      (symbol "C_1u_0402_22_1_1"
        (pin passive line (at 0 0 0) (length 2.032)
          (name "~" (effects (font (size 1.27 1.27))))
          (number "1" (effects (font (size 1.27 1.27))))
        )
        (pin passive line (at 5.08 0 180) (length 2.032)
          (name "~" (effects (font (size 1.27 1.27))))
          (number "2" (effects (font (size 1.27 1.27))))
        )
      )
    )
	(symbol "antmicroCapacitors0402:C_1u_0402_23" (pin_numbers hide) (pin_names hide) (in_bom yes) (on_board yes)
      (property "Reference" "C" (at 20.32 -5.08 0)
        (effects (font (size 1.27 1.27) (thickness 0.15)) (justify left bottom))
      )
      (property "Value" "C_1u_0402_23" (at 20.32 -10.16 0)
        (effects (font (size 1.27 1.27) (thickness 0.15)) (justify left bottom) hide)
      )
      (property "Footprint" "antmicro-footprints:C_0402_1005Metric" (at 20.32 -12.7 0)
        (effects (font (size 1.27 1.27) (thickness 0.15)) (justify left bottom) hide)
      )
      (property "Datasheet" " " (at 20.32 -15.24 0)
        (effects (font (size 1.27 1.27) (thickness 0.15)) (justify left bottom) hide)
      )
      (property "MPN" "C1005X6S1A105K050BC" (at 20.32 -17.78 0)
        (effects (font (size 1.27 1.27) (thickness 0.15)) (justify left bottom) hide)
      )
      (property "Manufacturer" "TDK" (at 20.32 -20.32 0)
        (effects (font (size 1.27 1.27) (thickness 0.15)) (justify left bottom) hide)
      )
      (property "License" "Apache-2.0" (at 20.32 -22.86 0)
        (effects (font (size 1.27 1.27) (thickness 0.15)) (justify left bottom) hide)
      )
      (property "Author" "Antmicro" (at 20.32 -25.4 0)
        (effects (font (size 1.27 1.27) (thickness 0.15)) (justify left bottom) hide)
      )
      (property "Val" "1u" (at 20.32 -7.62 0)
        (effects (font (size 1.27 1.27) (thickness 0.15)) (justify left bottom))
      )
      (property "Voltage" "" (at 20.32 -27.94 0)
        (effects (font (size 1.27 1.27)) (justify left bottom) hide)
      )
      (property "Dielectric" "" (at 20.32 -30.48 0)
        (effects (font (size 1.27 1.27)) (justify left bottom) hide)
      )
      (property "ki_description" " " (at 0 0 0)
        (effects (font (size 1.27 1.27)) hide)
      )
      (symbol "C_1u_0402_23_0_1"
        (polyline
          (pts
            (xy 2.032 -1.524)
            (xy 2.032 1.524)
          )
          (stroke (width 0.3048) (type default))
          (fill (type none))
        )
        (polyline
          (pts
            (xy 3.048 -1.524)
            (xy 3.048 1.524)
          )
          (stroke (width 0.3302) (type default))
          (fill (type none))
        )
      )
      (symbol "C_1u_0402_23_1_1"
        (pin passive line (at 0 0 0) (length 2.032)
          (name "~" (effects (font (size 1.27 1.27))))
          (number "1" (effects (font (size 1.27 1.27))))
        )
        (pin passive line (at 5.08 0 180) (length 2.032)
          (name "~" (effects (font (size 1.27 1.27))))
          (number "2" (effects (font (size 1.27 1.27))))
        )
      )
    )
	(symbol "antmicroCapacitors0402:C_1u_0402_24" (pin_numbers hide) (pin_names hide) (in_bom yes) (on_board yes)
      (property "Reference" "C" (at 20.32 -5.08 0)
        (effects (font (size 1.27 1.27) (thickness 0.15)) (justify left bottom))
      )
      (property "Value" "C_1u_0402_24" (at 20.32 -10.16 0)
        (effects (font (size 1.27 1.27) (thickness 0.15)) (justify left bottom) hide)
      )
      (property "Footprint" "antmicro-footprints:C_0402_1005Metric" (at 20.32 -12.7 0)
        (effects (font (size 1.27 1.27) (thickness 0.15)) (justify left bottom) hide)
      )
      (property "Datasheet" " " (at 20.32 -15.24 0)
        (effects (font (size 1.27 1.27) (thickness 0.15)) (justify left bottom) hide)
      )
      (property "MPN" "C1005X6S1A105K050BC" (at 20.32 -17.78 0)
        (effects (font (size 1.27 1.27) (thickness 0.15)) (justify left bottom) hide)
      )
      (property "Manufacturer" "TDK" (at 20.32 -20.32 0)
        (effects (font (size 1.27 1.27) (thickness 0.15)) (justify left bottom) hide)
      )
      (property "License" "Apache-2.0" (at 20.32 -22.86 0)
        (effects (font (size 1.27 1.27) (thickness 0.15)) (justify left bottom) hide)
      )
      (property "Author" "Antmicro" (at 20.32 -25.4 0)
        (effects (font (size 1.27 1.27) (thickness 0.15)) (justify left bottom) hide)
      )
      (property "Val" "1u" (at 20.32 -7.62 0)
        (effects (font (size 1.27 1.27) (thickness 0.15)) (justify left bottom))
      )
      (property "Voltage" "" (at 20.32 -27.94 0)
        (effects (font (size 1.27 1.27)) (justify left bottom) hide)
      )
      (property "Dielectric" "" (at 20.32 -30.48 0)
        (effects (font (size 1.27 1.27)) (justify left bottom) hide)
      )
      (property "ki_description" " " (at 0 0 0)
        (effects (font (size 1.27 1.27)) hide)
      )
      (symbol "C_1u_0402_24_0_1"
        (polyline
          (pts
            (xy 2.032 -1.524)
            (xy 2.032 1.524)
          )
          (stroke (width 0.3048) (type default))
          (fill (type none))
        )
        (polyline
          (pts
            (xy 3.048 -1.524)
            (xy 3.048 1.524)
          )
          (stroke (width 0.3302) (type default))
          (fill (type none))
        )
      )
      (symbol "C_1u_0402_24_1_1"
        (pin passive line (at 0 0 0) (length 2.032)
          (name "~" (effects (font (size 1.27 1.27))))
          (number "1" (effects (font (size 1.27 1.27))))
        )
        (pin passive line (at 5.08 0 180) (length 2.032)
          (name "~" (effects (font (size 1.27 1.27))))
          (number "2" (effects (font (size 1.27 1.27))))
        )
      )
    )
	(symbol "antmicroCapacitors0402:C_1u_0402_25" (pin_numbers hide) (pin_names hide) (in_bom yes) (on_board yes)
      (property "Reference" "C" (at 20.32 -5.08 0)
        (effects (font (size 1.27 1.27) (thickness 0.15)) (justify left bottom))
      )
      (property "Value" "C_1u_0402_25" (at 20.32 -10.16 0)
        (effects (font (size 1.27 1.27) (thickness 0.15)) (justify left bottom) hide)
      )
      (property "Footprint" "antmicro-footprints:C_0402_1005Metric" (at 20.32 -12.7 0)
        (effects (font (size 1.27 1.27) (thickness 0.15)) (justify left bottom) hide)
      )
      (property "Datasheet" " " (at 20.32 -15.24 0)
        (effects (font (size 1.27 1.27) (thickness 0.15)) (justify left bottom) hide)
      )
      (property "MPN" "C1005X6S1A105K050BC" (at 20.32 -17.78 0)
        (effects (font (size 1.27 1.27) (thickness 0.15)) (justify left bottom) hide)
      )
      (property "Manufacturer" "TDK" (at 20.32 -20.32 0)
        (effects (font (size 1.27 1.27) (thickness 0.15)) (justify left bottom) hide)
      )
      (property "License" "Apache-2.0" (at 20.32 -22.86 0)
        (effects (font (size 1.27 1.27) (thickness 0.15)) (justify left bottom) hide)
      )
      (property "Author" "Antmicro" (at 20.32 -25.4 0)
        (effects (font (size 1.27 1.27) (thickness 0.15)) (justify left bottom) hide)
      )
      (property "Val" "1u" (at 20.32 -7.62 0)
        (effects (font (size 1.27 1.27) (thickness 0.15)) (justify left bottom))
      )
      (property "Voltage" "" (at 20.32 -27.94 0)
        (effects (font (size 1.27 1.27)) (justify left bottom) hide)
      )
      (property "Dielectric" "" (at 20.32 -30.48 0)
        (effects (font (size 1.27 1.27)) (justify left bottom) hide)
      )
      (property "ki_description" " " (at 0 0 0)
        (effects (font (size 1.27 1.27)) hide)
      )
      (symbol "C_1u_0402_25_0_1"
        (polyline
          (pts
            (xy 2.032 -1.524)
            (xy 2.032 1.524)
          )
          (stroke (width 0.3048) (type default))
          (fill (type none))
        )
        (polyline
          (pts
            (xy 3.048 -1.524)
            (xy 3.048 1.524)
          )
          (stroke (width 0.3302) (type default))
          (fill (type none))
        )
      )
      (symbol "C_1u_0402_25_1_1"
        (pin passive line (at 0 0 0) (length 2.032)
          (name "~" (effects (font (size 1.27 1.27))))
          (number "1" (effects (font (size 1.27 1.27))))
        )
        (pin passive line (at 5.08 0 180) (length 2.032)
          (name "~" (effects (font (size 1.27 1.27))))
          (number "2" (effects (font (size 1.27 1.27))))
        )
      )
    )
	(symbol "antmicroCapacitors0402:C_1u_0402_26" (pin_numbers hide) (pin_names hide) (in_bom yes) (on_board yes)
      (property "Reference" "C" (at 20.32 -5.08 0)
        (effects (font (size 1.27 1.27) (thickness 0.15)) (justify left bottom))
      )
      (property "Value" "C_1u_0402_26" (at 20.32 -10.16 0)
        (effects (font (size 1.27 1.27) (thickness 0.15)) (justify left bottom) hide)
      )
      (property "Footprint" "antmicro-footprints:C_0402_1005Metric" (at 20.32 -12.7 0)
        (effects (font (size 1.27 1.27) (thickness 0.15)) (justify left bottom) hide)
      )
      (property "Datasheet" " " (at 20.32 -15.24 0)
        (effects (font (size 1.27 1.27) (thickness 0.15)) (justify left bottom) hide)
      )
      (property "MPN" "C1005X6S1A105K050BC" (at 20.32 -17.78 0)
        (effects (font (size 1.27 1.27) (thickness 0.15)) (justify left bottom) hide)
      )
      (property "Manufacturer" "TDK" (at 20.32 -20.32 0)
        (effects (font (size 1.27 1.27) (thickness 0.15)) (justify left bottom) hide)
      )
      (property "License" "Apache-2.0" (at 20.32 -22.86 0)
        (effects (font (size 1.27 1.27) (thickness 0.15)) (justify left bottom) hide)
      )
      (property "Author" "Antmicro" (at 20.32 -25.4 0)
        (effects (font (size 1.27 1.27) (thickness 0.15)) (justify left bottom) hide)
      )
      (property "Val" "1u" (at 20.32 -7.62 0)
        (effects (font (size 1.27 1.27) (thickness 0.15)) (justify left bottom))
      )
      (property "Voltage" "" (at 20.32 -27.94 0)
        (effects (font (size 1.27 1.27)) (justify left bottom) hide)
      )
      (property "Dielectric" "" (at 20.32 -30.48 0)
        (effects (font (size 1.27 1.27)) (justify left bottom) hide)
      )
      (property "ki_description" " " (at 0 0 0)
        (effects (font (size 1.27 1.27)) hide)
      )
      (symbol "C_1u_0402_26_0_1"
        (polyline
          (pts
            (xy 2.032 -1.524)
            (xy 2.032 1.524)
          )
          (stroke (width 0.3048) (type default))
          (fill (type none))
        )
        (polyline
          (pts
            (xy 3.048 -1.524)
            (xy 3.048 1.524)
          )
          (stroke (width 0.3302) (type default))
          (fill (type none))
        )
      )
      (symbol "C_1u_0402_26_1_1"
        (pin passive line (at 0 0 0) (length 2.032)
          (name "~" (effects (font (size 1.27 1.27))))
          (number "1" (effects (font (size 1.27 1.27))))
        )
        (pin passive line (at 5.08 0 180) (length 2.032)
          (name "~" (effects (font (size 1.27 1.27))))
          (number "2" (effects (font (size 1.27 1.27))))
        )
      )
    )
	(symbol "antmicroCapacitors0402:C_1u_0402_27" (pin_numbers hide) (pin_names hide) (in_bom yes) (on_board yes)
      (property "Reference" "C" (at 20.32 -5.08 0)
        (effects (font (size 1.27 1.27) (thickness 0.15)) (justify left bottom))
      )
      (property "Value" "C_1u_0402_27" (at 20.32 -10.16 0)
        (effects (font (size 1.27 1.27) (thickness 0.15)) (justify left bottom) hide)
      )
      (property "Footprint" "antmicro-footprints:C_0402_1005Metric" (at 20.32 -12.7 0)
        (effects (font (size 1.27 1.27) (thickness 0.15)) (justify left bottom) hide)
      )
      (property "Datasheet" " " (at 20.32 -15.24 0)
        (effects (font (size 1.27 1.27) (thickness 0.15)) (justify left bottom) hide)
      )
      (property "MPN" "C1005X6S1A105K050BC" (at 20.32 -17.78 0)
        (effects (font (size 1.27 1.27) (thickness 0.15)) (justify left bottom) hide)
      )
      (property "Manufacturer" "TDK" (at 20.32 -20.32 0)
        (effects (font (size 1.27 1.27) (thickness 0.15)) (justify left bottom) hide)
      )
      (property "License" "Apache-2.0" (at 20.32 -22.86 0)
        (effects (font (size 1.27 1.27) (thickness 0.15)) (justify left bottom) hide)
      )
      (property "Author" "Antmicro" (at 20.32 -25.4 0)
        (effects (font (size 1.27 1.27) (thickness 0.15)) (justify left bottom) hide)
      )
      (property "Val" "1u" (at 20.32 -7.62 0)
        (effects (font (size 1.27 1.27) (thickness 0.15)) (justify left bottom))
      )
      (property "Voltage" "" (at 20.32 -27.94 0)
        (effects (font (size 1.27 1.27)) (justify left bottom) hide)
      )
      (property "Dielectric" "" (at 20.32 -30.48 0)
        (effects (font (size 1.27 1.27)) (justify left bottom) hide)
      )
      (property "ki_description" " " (at 0 0 0)
        (effects (font (size 1.27 1.27)) hide)
      )
      (symbol "C_1u_0402_27_0_1"
        (polyline
          (pts
            (xy 2.032 -1.524)
            (xy 2.032 1.524)
          )
          (stroke (width 0.3048) (type default))
          (fill (type none))
        )
        (polyline
          (pts
            (xy 3.048 -1.524)
            (xy 3.048 1.524)
          )
          (stroke (width 0.3302) (type default))
          (fill (type none))
        )
      )
      (symbol "C_1u_0402_27_1_1"
        (pin passive line (at 0 0 0) (length 2.032)
          (name "~" (effects (font (size 1.27 1.27))))
          (number "1" (effects (font (size 1.27 1.27))))
        )
        (pin passive line (at 5.08 0 180) (length 2.032)
          (name "~" (effects (font (size 1.27 1.27))))
          (number "2" (effects (font (size 1.27 1.27))))
        )
      )
    )
	(symbol "antmicroCapacitors0402:C_1u_0402_28" (pin_numbers hide) (pin_names hide) (in_bom yes) (on_board yes)
      (property "Reference" "C" (at 20.32 -5.08 0)
        (effects (font (size 1.27 1.27) (thickness 0.15)) (justify left bottom))
      )
      (property "Value" "C_1u_0402_28" (at 20.32 -10.16 0)
        (effects (font (size 1.27 1.27) (thickness 0.15)) (justify left bottom) hide)
      )
      (property "Footprint" "antmicro-footprints:C_0402_1005Metric" (at 20.32 -12.7 0)
        (effects (font (size 1.27 1.27) (thickness 0.15)) (justify left bottom) hide)
      )
      (property "Datasheet" " " (at 20.32 -15.24 0)
        (effects (font (size 1.27 1.27) (thickness 0.15)) (justify left bottom) hide)
      )
      (property "MPN" "C1005X6S1A105K050BC" (at 20.32 -17.78 0)
        (effects (font (size 1.27 1.27) (thickness 0.15)) (justify left bottom) hide)
      )
      (property "Manufacturer" "TDK" (at 20.32 -20.32 0)
        (effects (font (size 1.27 1.27) (thickness 0.15)) (justify left bottom) hide)
      )
      (property "License" "Apache-2.0" (at 20.32 -22.86 0)
        (effects (font (size 1.27 1.27) (thickness 0.15)) (justify left bottom) hide)
      )
      (property "Author" "Antmicro" (at 20.32 -25.4 0)
        (effects (font (size 1.27 1.27) (thickness 0.15)) (justify left bottom) hide)
      )
      (property "Val" "1u" (at 20.32 -7.62 0)
        (effects (font (size 1.27 1.27) (thickness 0.15)) (justify left bottom))
      )
      (property "Voltage" "" (at 20.32 -27.94 0)
        (effects (font (size 1.27 1.27)) (justify left bottom) hide)
      )
      (property "Dielectric" "" (at 20.32 -30.48 0)
        (effects (font (size 1.27 1.27)) (justify left bottom) hide)
      )
      (property "ki_description" " " (at 0 0 0)
        (effects (font (size 1.27 1.27)) hide)
      )
      (symbol "C_1u_0402_28_0_1"
        (polyline
          (pts
            (xy 2.032 -1.524)
            (xy 2.032 1.524)
          )
          (stroke (width 0.3048) (type default))
          (fill (type none))
        )
        (polyline
          (pts
            (xy 3.048 -1.524)
            (xy 3.048 1.524)
          )
          (stroke (width 0.3302) (type default))
          (fill (type none))
        )
      )
      (symbol "C_1u_0402_28_1_1"
        (pin passive line (at 0 0 0) (length 2.032)
          (name "~" (effects (font (size 1.27 1.27))))
          (number "1" (effects (font (size 1.27 1.27))))
        )
        (pin passive line (at 5.08 0 180) (length 2.032)
          (name "~" (effects (font (size 1.27 1.27))))
          (number "2" (effects (font (size 1.27 1.27))))
        )
      )
    )
	(symbol "antmicroCapacitors0402:C_1u_0402_29" (pin_numbers hide) (pin_names hide) (in_bom yes) (on_board yes)
      (property "Reference" "C" (at 20.32 -5.08 0)
        (effects (font (size 1.27 1.27) (thickness 0.15)) (justify left bottom))
      )
      (property "Value" "C_1u_0402_29" (at 20.32 -10.16 0)
        (effects (font (size 1.27 1.27) (thickness 0.15)) (justify left bottom) hide)
      )
      (property "Footprint" "antmicro-footprints:C_0402_1005Metric" (at 20.32 -12.7 0)
        (effects (font (size 1.27 1.27) (thickness 0.15)) (justify left bottom) hide)
      )
      (property "Datasheet" " " (at 20.32 -15.24 0)
        (effects (font (size 1.27 1.27) (thickness 0.15)) (justify left bottom) hide)
      )
      (property "MPN" "C1005X6S1A105K050BC" (at 20.32 -17.78 0)
        (effects (font (size 1.27 1.27) (thickness 0.15)) (justify left bottom) hide)
      )
      (property "Manufacturer" "TDK" (at 20.32 -20.32 0)
        (effects (font (size 1.27 1.27) (thickness 0.15)) (justify left bottom) hide)
      )
      (property "License" "Apache-2.0" (at 20.32 -22.86 0)
        (effects (font (size 1.27 1.27) (thickness 0.15)) (justify left bottom) hide)
      )
      (property "Author" "Antmicro" (at 20.32 -25.4 0)
        (effects (font (size 1.27 1.27) (thickness 0.15)) (justify left bottom) hide)
      )
      (property "Val" "1u" (at 20.32 -7.62 0)
        (effects (font (size 1.27 1.27) (thickness 0.15)) (justify left bottom))
      )
      (property "Voltage" "" (at 20.32 -27.94 0)
        (effects (font (size 1.27 1.27)) (justify left bottom) hide)
      )
      (property "Dielectric" "" (at 20.32 -30.48 0)
        (effects (font (size 1.27 1.27)) (justify left bottom) hide)
      )
      (property "ki_description" " " (at 0 0 0)
        (effects (font (size 1.27 1.27)) hide)
      )
      (symbol "C_1u_0402_29_0_1"
        (polyline
          (pts
            (xy 2.032 -1.524)
            (xy 2.032 1.524)
          )
          (stroke (width 0.3048) (type default))
          (fill (type none))
        )
        (polyline
          (pts
            (xy 3.048 -1.524)
            (xy 3.048 1.524)
          )
          (stroke (width 0.3302) (type default))
          (fill (type none))
        )
      )
      (symbol "C_1u_0402_29_1_1"
        (pin passive line (at 0 0 0) (length 2.032)
          (name "~" (effects (font (size 1.27 1.27))))
          (number "1" (effects (font (size 1.27 1.27))))
        )
        (pin passive line (at 5.08 0 180) (length 2.032)
          (name "~" (effects (font (size 1.27 1.27))))
          (number "2" (effects (font (size 1.27 1.27))))
        )
      )
    )
	(symbol "antmicroCapacitors0402:C_220n_0402" (pin_numbers hide) (pin_names hide) (in_bom yes) (on_board yes)
      (property "Reference" "C" (at 20.32 -5.08 0)
        (effects (font (size 1.27 1.27) (thickness 0.15)) (justify left bottom))
      )
      (property "Value" "C_220n_0402" (at 20.32 -10.16 0)
        (effects (font (size 1.27 1.27) (thickness 0.15)) (justify left bottom) hide)
      )
      (property "Footprint" "antmicro-footprints:C_0402_1005Metric" (at 20.32 -12.7 0)
        (effects (font (size 1.27 1.27) (thickness 0.15)) (justify left bottom) hide)
      )
      (property "Datasheet" "https://www.yageo.com/en/Chart/Download/pdf/CC0402KRX5R6BB224" (at 20.32 -15.24 0)
        (effects (font (size 1.27 1.27) (thickness 0.15)) (justify left bottom) hide)
      )
      (property "MPN" "CC0402KRX5R6BB224" (at 20.32 -17.78 0)
        (effects (font (size 1.27 1.27) (thickness 0.15)) (justify left bottom) hide)
      )
      (property "Manufacturer" "YAGEO" (at 20.32 -20.32 0)
        (effects (font (size 1.27 1.27) (thickness 0.15)) (justify left bottom) hide)
      )
      (property "License" "Apache-2.0" (at 20.32 -22.86 0)
        (effects (font (size 1.27 1.27) (thickness 0.15)) (justify left bottom) hide)
      )
      (property "Author" "Antmicro" (at 20.32 -25.4 0)
        (effects (font (size 1.27 1.27) (thickness 0.15)) (justify left bottom) hide)
      )
      (property "Val" "220n" (at 20.32 -7.62 0)
        (effects (font (size 1.27 1.27) (thickness 0.15)) (justify left bottom))
      )
      (property "Voltage" "" (at 20.32 -27.94 0)
        (effects (font (size 1.27 1.27)) (justify left bottom) hide)
      )
      (property "Dielectric" "" (at 20.32 -30.48 0)
        (effects (font (size 1.27 1.27)) (justify left bottom) hide)
      )
      (property "ki_keywords" "0402, SMT, CAPACITOR, PASSIVE, MLCC, CERAMIC" (at 0 0 0)
        (effects (font (size 1.27 1.27)) hide)
      )
      (property "ki_description" "SMD Multilayer Ceramic Capacitor, 0.22 µF, 10 V, 0402 [1005 Metric], ± 10%, X5R, CC Series" (at 0 0 0)
        (effects (font (size 1.27 1.27)) hide)
      )
      (symbol "C_220n_0402_0_1"
        (polyline
          (pts
            (xy 2.032 -1.524)
            (xy 2.032 1.524)
          )
          (stroke (width 0.3048) (type default))
          (fill (type none))
        )
        (polyline
          (pts
            (xy 3.048 -1.524)
            (xy 3.048 1.524)
          )
          (stroke (width 0.3302) (type default))
          (fill (type none))
        )
      )
      (symbol "C_220n_0402_1_1"
        (pin passive line (at 0 0 0) (length 2.032)
          (name "~" (effects (font (size 1.27 1.27))))
          (number "1" (effects (font (size 1.27 1.27))))
        )
        (pin passive line (at 5.08 0 180) (length 2.032)
          (name "~" (effects (font (size 1.27 1.27))))
          (number "2" (effects (font (size 1.27 1.27))))
        )
      )
    )
	(symbol "antmicroCapacitors0402:C_220n_0402_10" (pin_numbers hide) (pin_names hide) (in_bom yes) (on_board yes)
      (property "Reference" "C" (at 20.32 -5.08 0)
        (effects (font (size 1.27 1.27) (thickness 0.15)) (justify left bottom))
      )
      (property "Value" "C_220n_0402_10" (at 20.32 -10.16 0)
        (effects (font (size 1.27 1.27) (thickness 0.15)) (justify left bottom) hide)
      )
      (property "Footprint" "antmicro-footprints:C_0402_1005Metric" (at 20.32 -12.7 0)
        (effects (font (size 1.27 1.27) (thickness 0.15)) (justify left bottom) hide)
      )
      (property "Datasheet" " " (at 20.32 -15.24 0)
        (effects (font (size 1.27 1.27) (thickness 0.15)) (justify left bottom) hide)
      )
      (property "MPN" "CC0402KRX5R6BB224" (at 20.32 -17.78 0)
        (effects (font (size 1.27 1.27) (thickness 0.15)) (justify left bottom) hide)
      )
      (property "Manufacturer" "Yaego" (at 20.32 -20.32 0)
        (effects (font (size 1.27 1.27) (thickness 0.15)) (justify left bottom) hide)
      )
      (property "License" "Apache-2.0" (at 20.32 -22.86 0)
        (effects (font (size 1.27 1.27) (thickness 0.15)) (justify left bottom) hide)
      )
      (property "Author" "Antmicro" (at 20.32 -25.4 0)
        (effects (font (size 1.27 1.27) (thickness 0.15)) (justify left bottom) hide)
      )
      (property "Val" "220n" (at 20.32 -7.62 0)
        (effects (font (size 1.27 1.27) (thickness 0.15)) (justify left bottom))
      )
      (property "Voltage" "" (at 20.32 -27.94 0)
        (effects (font (size 1.27 1.27)) (justify left bottom) hide)
      )
      (property "Dielectric" "" (at 20.32 -30.48 0)
        (effects (font (size 1.27 1.27)) (justify left bottom) hide)
      )
      (property "ki_description" " " (at 0 0 0)
        (effects (font (size 1.27 1.27)) hide)
      )
      (symbol "C_220n_0402_10_0_1"
        (polyline
          (pts
            (xy 2.032 -1.524)
            (xy 2.032 1.524)
          )
          (stroke (width 0.3048) (type default))
          (fill (type none))
        )
        (polyline
          (pts
            (xy 3.048 -1.524)
            (xy 3.048 1.524)
          )
          (stroke (width 0.3302) (type default))
          (fill (type none))
        )
      )
      (symbol "C_220n_0402_10_1_1"
        (pin passive line (at 0 0 0) (length 2.032)
          (name "~" (effects (font (size 1.27 1.27))))
          (number "1" (effects (font (size 1.27 1.27))))
        )
        (pin passive line (at 5.08 0 180) (length 2.032)
          (name "~" (effects (font (size 1.27 1.27))))
          (number "2" (effects (font (size 1.27 1.27))))
        )
      )
    )
	(symbol "antmicroCapacitors0402:C_220n_0402_11" (pin_numbers hide) (pin_names hide) (in_bom yes) (on_board yes)
      (property "Reference" "C" (at 20.32 -5.08 0)
        (effects (font (size 1.27 1.27) (thickness 0.15)) (justify left bottom))
      )
      (property "Value" "C_220n_0402_11" (at 20.32 -10.16 0)
        (effects (font (size 1.27 1.27) (thickness 0.15)) (justify left bottom) hide)
      )
      (property "Footprint" "antmicro-footprints:C_0402_1005Metric" (at 20.32 -12.7 0)
        (effects (font (size 1.27 1.27) (thickness 0.15)) (justify left bottom) hide)
      )
      (property "Datasheet" " " (at 20.32 -15.24 0)
        (effects (font (size 1.27 1.27) (thickness 0.15)) (justify left bottom) hide)
      )
      (property "MPN" "CC0402KRX5R6BB224" (at 20.32 -17.78 0)
        (effects (font (size 1.27 1.27) (thickness 0.15)) (justify left bottom) hide)
      )
      (property "Manufacturer" "Yaego" (at 20.32 -20.32 0)
        (effects (font (size 1.27 1.27) (thickness 0.15)) (justify left bottom) hide)
      )
      (property "License" "Apache-2.0" (at 20.32 -22.86 0)
        (effects (font (size 1.27 1.27) (thickness 0.15)) (justify left bottom) hide)
      )
      (property "Author" "Antmicro" (at 20.32 -25.4 0)
        (effects (font (size 1.27 1.27) (thickness 0.15)) (justify left bottom) hide)
      )
      (property "Val" "220n" (at 20.32 -7.62 0)
        (effects (font (size 1.27 1.27) (thickness 0.15)) (justify left bottom))
      )
      (property "Voltage" "" (at 20.32 -27.94 0)
        (effects (font (size 1.27 1.27)) (justify left bottom) hide)
      )
      (property "Dielectric" "" (at 20.32 -30.48 0)
        (effects (font (size 1.27 1.27)) (justify left bottom) hide)
      )
      (property "ki_description" " " (at 0 0 0)
        (effects (font (size 1.27 1.27)) hide)
      )
      (symbol "C_220n_0402_11_0_1"
        (polyline
          (pts
            (xy 2.032 -1.524)
            (xy 2.032 1.524)
          )
          (stroke (width 0.3048) (type default))
          (fill (type none))
        )
        (polyline
          (pts
            (xy 3.048 -1.524)
            (xy 3.048 1.524)
          )
          (stroke (width 0.3302) (type default))
          (fill (type none))
        )
      )
      (symbol "C_220n_0402_11_1_1"
        (pin passive line (at 0 0 0) (length 2.032)
          (name "~" (effects (font (size 1.27 1.27))))
          (number "1" (effects (font (size 1.27 1.27))))
        )
        (pin passive line (at 5.08 0 180) (length 2.032)
          (name "~" (effects (font (size 1.27 1.27))))
          (number "2" (effects (font (size 1.27 1.27))))
        )
      )
    )
	(symbol "antmicroCapacitors0402:C_220p_0402" (pin_numbers hide) (pin_names hide) (in_bom yes) (on_board yes)
      (property "Reference" "C" (at 20.32 -5.08 0)
        (effects (font (size 1.27 1.27) (thickness 0.15)) (justify left bottom))
      )
      (property "Value" "C_220p_0402" (at 20.32 -10.16 0)
        (effects (font (size 1.27 1.27) (thickness 0.15)) (justify left bottom) hide)
      )
      (property "Footprint" "antmicro-footprints:C_0402_1005Metric" (at 20.32 -12.7 0)
        (effects (font (size 1.27 1.27) (thickness 0.15)) (justify left bottom) hide)
      )
      (property "Datasheet" "https://spicat.kyocera-avx.com/product/mlcc/chartview/04025C221JAT2A/" (at 20.32 -15.24 0)
        (effects (font (size 1.27 1.27) (thickness 0.15)) (justify left bottom) hide)
      )
      (property "MPN" "04025C221JAT2A" (at 20.32 -17.78 0)
        (effects (font (size 1.27 1.27) (thickness 0.15)) (justify left bottom) hide)
      )
      (property "Manufacturer" "KYOCERA AVX" (at 20.32 -20.32 0)
        (effects (font (size 1.27 1.27) (thickness 0.15)) (justify left bottom) hide)
      )
      (property "License" "Apache-2.0" (at 20.32 -22.86 0)
        (effects (font (size 1.27 1.27) (thickness 0.15)) (justify left bottom) hide)
      )
      (property "Author" "Antmicro" (at 20.32 -25.4 0)
        (effects (font (size 1.27 1.27) (thickness 0.15)) (justify left bottom) hide)
      )
      (property "Val" "220p" (at 20.32 -7.62 0)
        (effects (font (size 1.27 1.27) (thickness 0.15)) (justify left bottom))
      )
      (property "Voltage" "" (at 20.32 -27.94 0)
        (effects (font (size 1.27 1.27)) (justify left bottom) hide)
      )
      (property "Dielectric" "" (at 20.32 -30.48 0)
        (effects (font (size 1.27 1.27)) (justify left bottom) hide)
      )
      (property "ki_keywords" "0402, SMT, CAPACITOR, PASSIVE" (at 0 0 0)
        (effects (font (size 1.27 1.27)) hide)
      )
      (property "ki_description" "SMD Multilayer Ceramic Capacitor, 220 pF, 50 V, 0402 [1005 Metric], ± 10%, X7R, MC" (at 0 0 0)
        (effects (font (size 1.27 1.27)) hide)
      )
      (symbol "C_220p_0402_0_1"
        (polyline
          (pts
            (xy 2.032 -1.524)
            (xy 2.032 1.524)
          )
          (stroke (width 0.3048) (type default))
          (fill (type none))
        )
        (polyline
          (pts
            (xy 3.048 -1.524)
            (xy 3.048 1.524)
          )
          (stroke (width 0.3302) (type default))
          (fill (type none))
        )
      )
      (symbol "C_220p_0402_1_1"
        (pin passive line (at 0 0 0) (length 2.032)
          (name "~" (effects (font (size 1.27 1.27))))
          (number "1" (effects (font (size 1.27 1.27))))
        )
        (pin passive line (at 5.08 0 180) (length 2.032)
          (name "~" (effects (font (size 1.27 1.27))))
          (number "2" (effects (font (size 1.27 1.27))))
        )
      )
    )
	(symbol "antmicroCapacitors0402:C_22n_0402" (pin_numbers hide) (pin_names hide) (in_bom yes) (on_board yes)
      (property "Reference" "C" (at 20.32 -5.08 0)
        (effects (font (size 1.27 1.27) (thickness 0.15)) (justify left bottom))
      )
      (property "Value" "C_22n_0402" (at 20.32 -10.16 0)
        (effects (font (size 1.27 1.27) (thickness 0.15)) (justify left bottom) hide)
      )
      (property "Footprint" "antmicro-footprints:C_0402_1005Metric" (at 20.32 -12.7 0)
        (effects (font (size 1.27 1.27) (thickness 0.15)) (justify left bottom) hide)
      )
      (property "Datasheet" "https://www.murata.com/products/productdetail?partno=GCM155R71H223MA55%23" (at 20.32 -15.24 0)
        (effects (font (size 1.27 1.27) (thickness 0.15)) (justify left bottom) hide)
      )
      (property "MPN" "GCM155R71H223MA55D" (at 20.32 -17.78 0)
        (effects (font (size 1.27 1.27) (thickness 0.15)) (justify left bottom) hide)
      )
      (property "Manufacturer" "Murata" (at 20.32 -20.32 0)
        (effects (font (size 1.27 1.27) (thickness 0.15)) (justify left bottom) hide)
      )
      (property "License" "Apache-2.0" (at 20.32 -22.86 0)
        (effects (font (size 1.27 1.27) (thickness 0.15)) (justify left bottom) hide)
      )
      (property "Author" "Antmicro" (at 20.32 -25.4 0)
        (effects (font (size 1.27 1.27) (thickness 0.15)) (justify left bottom) hide)
      )
      (property "Val" "22n" (at 20.32 -7.62 0)
        (effects (font (size 1.27 1.27) (thickness 0.15)) (justify left bottom))
      )
      (property "Voltage" "" (at 20.32 -27.94 0)
        (effects (font (size 1.27 1.27)) (justify left bottom) hide)
      )
      (property "Dielectric" "" (at 20.32 -30.48 0)
        (effects (font (size 1.27 1.27)) (justify left bottom) hide)
      )
      (property "ki_keywords" "0402, SMT, CAPACITOR, PASSIVE, CERAMIC, MLCC" (at 0 0 0)
        (effects (font (size 1.27 1.27)) hide)
      )
      (property "ki_description" "SMD Multilayer Ceramic Capacitors, 0.022 µF, 50 V, 20%, 0402 [1005 Metric], X7R" (at 0 0 0)
        (effects (font (size 1.27 1.27)) hide)
      )
      (symbol "C_22n_0402_0_1"
        (polyline
          (pts
            (xy 2.032 -1.524)
            (xy 2.032 1.524)
          )
          (stroke (width 0.3048) (type default))
          (fill (type none))
        )
        (polyline
          (pts
            (xy 3.048 -1.524)
            (xy 3.048 1.524)
          )
          (stroke (width 0.3302) (type default))
          (fill (type none))
        )
      )
      (symbol "C_22n_0402_1_1"
        (pin passive line (at 0 0 0) (length 2.032)
          (name "~" (effects (font (size 1.27 1.27))))
          (number "1" (effects (font (size 1.27 1.27))))
        )
        (pin passive line (at 5.08 0 180) (length 2.032)
          (name "~" (effects (font (size 1.27 1.27))))
          (number "2" (effects (font (size 1.27 1.27))))
        )
      )
    )
	(symbol "antmicroCapacitors0402:C_2u2_0402" (pin_numbers hide) (pin_names hide) (in_bom yes) (on_board yes)
      (property "Reference" "C" (at 20.32 -5.08 0)
        (effects (font (size 1.27 1.27) (thickness 0.15)) (justify left bottom))
      )
      (property "Value" "C_2u2_0402" (at 20.32 -10.16 0)
        (effects (font (size 1.27 1.27) (thickness 0.15)) (justify left bottom) hide)
      )
      (property "Footprint" "antmicro-footprints:C_0402_1005Metric" (at 20.32 -12.7 0)
        (effects (font (size 1.27 1.27) (thickness 0.15)) (justify left bottom) hide)
      )
      (property "Datasheet" "https://product.tdk.com/en/search/capacitor/ceramic/mlcc/info?part_no=C1005X5R1A225K050BC" (at 20.32 -15.24 0)
        (effects (font (size 1.27 1.27) (thickness 0.15)) (justify left bottom) hide)
      )
      (property "MPN" "C1005X5R1A225K050BC" (at 20.32 -17.78 0)
        (effects (font (size 1.27 1.27) (thickness 0.15)) (justify left bottom) hide)
      )
      (property "Manufacturer" "TDK" (at 20.32 -20.32 0)
        (effects (font (size 1.27 1.27) (thickness 0.15)) (justify left bottom) hide)
      )
      (property "License" "Apache-2.0" (at 20.32 -22.86 0)
        (effects (font (size 1.27 1.27) (thickness 0.15)) (justify left bottom) hide)
      )
      (property "Author" "Antmicro" (at 20.32 -25.4 0)
        (effects (font (size 1.27 1.27) (thickness 0.15)) (justify left bottom) hide)
      )
      (property "Val" "2u2" (at 20.32 -7.62 0)
        (effects (font (size 1.27 1.27) (thickness 0.15)) (justify left bottom))
      )
      (property "Voltage" "" (at 20.32 -27.94 0)
        (effects (font (size 1.27 1.27)) (justify left bottom) hide)
      )
      (property "Dielectric" "" (at 20.32 -30.48 0)
        (effects (font (size 1.27 1.27)) (justify left bottom) hide)
      )
      (property "ki_keywords" "0402, SMT, CAPACITOR, PASSIVE, CERAMIC, MLCC" (at 0 0 0)
        (effects (font (size 1.27 1.27)) hide)
      )
      (property "ki_description" "SMD Multilayer Ceramic Capacitor, 2.2 µF, 10 V, 0402 [1005 Metric], ± 10%, X5R, C" (at 0 0 0)
        (effects (font (size 1.27 1.27)) hide)
      )
      (symbol "C_2u2_0402_0_1"
        (polyline
          (pts
            (xy 2.032 -1.524)
            (xy 2.032 1.524)
          )
          (stroke (width 0.3048) (type default))
          (fill (type none))
        )
        (polyline
          (pts
            (xy 3.048 -1.524)
            (xy 3.048 1.524)
          )
          (stroke (width 0.3302) (type default))
          (fill (type none))
        )
      )
      (symbol "C_2u2_0402_1_1"
        (pin passive line (at 0 0 0) (length 2.032)
          (name "~" (effects (font (size 1.27 1.27))))
          (number "1" (effects (font (size 1.27 1.27))))
        )
        (pin passive line (at 5.08 0 180) (length 2.032)
          (name "~" (effects (font (size 1.27 1.27))))
          (number "2" (effects (font (size 1.27 1.27))))
        )
      )
    )
	(symbol "antmicroCapacitors0402:C_33p_0402" (pin_numbers hide) (pin_names hide) (in_bom yes) (on_board yes)
      (property "Reference" "C" (at 20.32 -5.08 0)
        (effects (font (size 1.27 1.27) (thickness 0.15)) (justify left bottom))
      )
      (property "Value" "C_33p_0402" (at 20.32 -10.16 0)
        (effects (font (size 1.27 1.27) (thickness 0.15)) (justify left bottom) hide)
      )
      (property "Footprint" "antmicro-footprints:C_0402_1005Metric" (at 20.32 -12.7 0)
        (effects (font (size 1.27 1.27) (thickness 0.15)) (justify left bottom) hide)
      )
      (property "Datasheet" "https://spicat.kyocera-avx.com/product/mlcc/chartview/04025A330FAT2A/" (at 20.32 -15.24 0)
        (effects (font (size 1.27 1.27) (thickness 0.15)) (justify left bottom) hide)
      )
      (property "MPN" "04025A330FAT2A" (at 20.32 -17.78 0)
        (effects (font (size 1.27 1.27) (thickness 0.15)) (justify left bottom) hide)
      )
      (property "Manufacturer" "KYOCERA AVX" (at 20.32 -20.32 0)
        (effects (font (size 1.27 1.27) (thickness 0.15)) (justify left bottom) hide)
      )
      (property "License" "Apache-2.0" (at 20.32 -22.86 0)
        (effects (font (size 1.27 1.27) (thickness 0.15)) (justify left bottom) hide)
      )
      (property "Author" "Antmicro" (at 20.32 -25.4 0)
        (effects (font (size 1.27 1.27) (thickness 0.15)) (justify left bottom) hide)
      )
      (property "Val" "33p" (at 20.32 -7.62 0)
        (effects (font (size 1.27 1.27) (thickness 0.15)) (justify left bottom))
      )
      (property "Voltage" "" (at 20.32 -27.94 0)
        (effects (font (size 1.27 1.27)) (justify left bottom) hide)
      )
      (property "Dielectric" "" (at 20.32 -30.48 0)
        (effects (font (size 1.27 1.27)) (justify left bottom) hide)
      )
      (property "ki_keywords" "0402, SMT, CAPACITOR, PASSIVE" (at 0 0 0)
        (effects (font (size 1.27 1.27)) hide)
      )
      (property "ki_description" "SMD Multilayer Ceramic Capacitor, 33 pF, 50 V, 0402 [1005 Metric], ± 5%, C0G / NP0, MC" (at 0 0 0)
        (effects (font (size 1.27 1.27)) hide)
      )
      (symbol "C_33p_0402_0_1"
        (polyline
          (pts
            (xy 2.032 -1.524)
            (xy 2.032 1.524)
          )
          (stroke (width 0.3048) (type default))
          (fill (type none))
        )
        (polyline
          (pts
            (xy 3.048 -1.524)
            (xy 3.048 1.524)
          )
          (stroke (width 0.3302) (type default))
          (fill (type none))
        )
      )
      (symbol "C_33p_0402_1_1"
        (pin passive line (at 0 0 0) (length 2.032)
          (name "~" (effects (font (size 1.27 1.27))))
          (number "1" (effects (font (size 1.27 1.27))))
        )
        (pin passive line (at 5.08 0 180) (length 2.032)
          (name "~" (effects (font (size 1.27 1.27))))
          (number "2" (effects (font (size 1.27 1.27))))
        )
      )
    )
	(symbol "antmicroCapacitors0402:C_4n7_0402" (pin_numbers hide) (pin_names hide) (in_bom yes) (on_board yes)
      (property "Reference" "C" (at 20.32 -5.08 0)
        (effects (font (size 1.27 1.27) (thickness 0.15)) (justify left bottom))
      )
      (property "Value" "C_4n7_0402" (at 20.32 -10.16 0)
        (effects (font (size 1.27 1.27) (thickness 0.15)) (justify left bottom) hide)
      )
      (property "Footprint" "antmicro-footprints:C_0402_1005Metric" (at 20.32 -12.7 0)
        (effects (font (size 1.27 1.27) (thickness 0.15)) (justify left bottom) hide)
      )
      (property "Datasheet" "https://product.tdk.com/en/search/capacitor/ceramic/mlcc/info?part_no=CGA2B3X7S2A472K050BB" (at 20.32 -15.24 0)
        (effects (font (size 1.27 1.27) (thickness 0.15)) (justify left bottom) hide)
      )
      (property "MPN" "CGA2B3X7S2A472K050BB" (at 20.32 -17.78 0)
        (effects (font (size 1.27 1.27) (thickness 0.15)) (justify left bottom) hide)
      )
      (property "Manufacturer" "TDK" (at 20.32 -20.32 0)
        (effects (font (size 1.27 1.27) (thickness 0.15)) (justify left bottom) hide)
      )
      (property "License" "Apache-2.0" (at 20.32 -22.86 0)
        (effects (font (size 1.27 1.27) (thickness 0.15)) (justify left bottom) hide)
      )
      (property "Author" "Antmicro" (at 20.32 -25.4 0)
        (effects (font (size 1.27 1.27) (thickness 0.15)) (justify left bottom) hide)
      )
      (property "Val" "4n7" (at 20.32 -7.62 0)
        (effects (font (size 1.27 1.27) (thickness 0.15)) (justify left bottom))
      )
      (property "Voltage" "" (at 20.32 -27.94 0)
        (effects (font (size 1.27 1.27)) (justify left bottom) hide)
      )
      (property "Dielectric" "" (at 20.32 -30.48 0)
        (effects (font (size 1.27 1.27)) (justify left bottom) hide)
      )
      (property "ki_keywords" "0402, SMT, CAPACITOR, PASSIVE, CERAMIC, MLCC" (at 0 0 0)
        (effects (font (size 1.27 1.27)) hide)
      )
      (property "ki_description" "SMD Multilayer Ceramic Capacitor, 4700 pF, 100 V, 0402 [1005 Metric], ± 10%, X7S, CGA" (at 0 0 0)
        (effects (font (size 1.27 1.27)) hide)
      )
      (symbol "C_4n7_0402_0_1"
        (polyline
          (pts
            (xy 2.032 -1.524)
            (xy 2.032 1.524)
          )
          (stroke (width 0.3048) (type default))
          (fill (type none))
        )
        (polyline
          (pts
            (xy 3.048 -1.524)
            (xy 3.048 1.524)
          )
          (stroke (width 0.3302) (type default))
          (fill (type none))
        )
      )
      (symbol "C_4n7_0402_1_1"
        (pin passive line (at 0 0 0) (length 2.032)
          (name "~" (effects (font (size 1.27 1.27))))
          (number "1" (effects (font (size 1.27 1.27))))
        )
        (pin passive line (at 5.08 0 180) (length 2.032)
          (name "~" (effects (font (size 1.27 1.27))))
          (number "2" (effects (font (size 1.27 1.27))))
        )
      )
    )
	(symbol "antmicroCapacitors0402:C_4u7_25V_0402" (pin_numbers hide) (pin_names hide) (in_bom yes) (on_board yes)
      (property "Reference" "C" (at 20.32 -5.08 0)
        (effects (font (size 1.27 1.27) (thickness 0.15)) (justify left bottom))
      )
      (property "Value" "C_4u7_25V_0402" (at 20.32 -10.16 0)
        (effects (font (size 1.27 1.27) (thickness 0.15)) (justify left bottom) hide)
      )
      (property "Footprint" "antmicro-footprints:C_0402_1005Metric" (at 20.32 -12.7 0)
        (effects (font (size 1.27 1.27) (thickness 0.15)) (justify left bottom) hide)
      )
      (property "Datasheet" "https://www.murata.com/products/productdetail?partno=GRM155C61E475ME15%23" (at 20.32 -15.24 0)
        (effects (font (size 1.27 1.27) (thickness 0.15)) (justify left bottom) hide)
      )
      (property "MPN" "GRM155C61E475ME15J" (at 20.32 -17.78 0)
        (effects (font (size 1.27 1.27) (thickness 0.15)) (justify left bottom) hide)
      )
      (property "Manufacturer" "Murata" (at 20.32 -20.32 0)
        (effects (font (size 1.27 1.27) (thickness 0.15)) (justify left bottom) hide)
      )
      (property "License" "Apache-2.0" (at 20.32 -22.86 0)
        (effects (font (size 1.27 1.27) (thickness 0.15)) (justify left bottom) hide)
      )
      (property "Author" "Antmicro" (at 20.32 -25.4 0)
        (effects (font (size 1.27 1.27) (thickness 0.15)) (justify left bottom) hide)
      )
      (property "Val" "4u7" (at 20.32 -7.62 0)
        (effects (font (size 1.27 1.27) (thickness 0.15)) (justify left bottom))
      )
      (property "Voltage" "25V" (at 20.32 -27.94 0)
        (effects (font (size 1.27 1.27)) (justify left bottom) hide)
      )
      (property "Dielectric" "X5S" (at 20.32 -30.48 0)
        (effects (font (size 1.27 1.27)) (justify left bottom) hide)
      )
      (property "ki_keywords" "0402, SMT, CAPACITOR, PASSIVE, CERAMIC" (at 0 0 0)
        (effects (font (size 1.27 1.27)) hide)
      )
      (property "ki_description" "SMD Multilayer Ceramic Capacitor" (at 0 0 0)
        (effects (font (size 1.27 1.27)) hide)
      )
      (symbol "C_4u7_25V_0402_0_1"
        (polyline
          (pts
            (xy 2.032 -1.524)
            (xy 2.032 1.524)
          )
          (stroke (width 0.3048) (type default))
          (fill (type none))
        )
        (polyline
          (pts
            (xy 3.048 -1.524)
            (xy 3.048 1.524)
          )
          (stroke (width 0.3302) (type default))
          (fill (type none))
        )
      )
      (symbol "C_4u7_25V_0402_1_1"
        (pin passive line (at 0 0 0) (length 2.032)
          (name "~" (effects (font (size 1.27 1.27))))
          (number "1" (effects (font (size 1.27 1.27))))
        )
        (pin passive line (at 5.08 0 180) (length 2.032)
          (name "~" (effects (font (size 1.27 1.27))))
          (number "2" (effects (font (size 1.27 1.27))))
        )
      )
    )
	(symbol "antmicroCapacitors0603:C_22u_0603" (pin_numbers hide) (pin_names hide) (in_bom yes) (on_board yes)
      (property "Reference" "C" (at 20.32 -5.08 0)
        (effects (font (size 1.27 1.27) (thickness 0.15)) (justify left bottom))
      )
      (property "Value" "C_22u_0603" (at 20.32 -10.16 0)
        (effects (font (size 1.27 1.27) (thickness 0.15)) (justify left bottom) hide)
      )
      (property "Footprint" "antmicro-footprints:C_0603_1608Metric" (at 20.32 -12.7 0)
        (effects (font (size 1.27 1.27) (thickness 0.15)) (justify left bottom) hide)
      )
      (property "Datasheet" "https://www.murata.com/products/productdetail?partno=GRM188R60J226MEA0%23" (at 20.32 -15.24 0)
        (effects (font (size 1.27 1.27) (thickness 0.15)) (justify left bottom) hide)
      )
      (property "MPN" "GRM188R60J226MEA0D" (at 20.32 -17.78 0)
        (effects (font (size 1.27 1.27) (thickness 0.15)) (justify left bottom) hide)
      )
      (property "Manufacturer" "Murata" (at 20.32 -20.32 0)
        (effects (font (size 1.27 1.27) (thickness 0.15)) (justify left bottom) hide)
      )
      (property "License" "Apache-2.0" (at 20.32 -22.86 0)
        (effects (font (size 1.27 1.27) (thickness 0.15)) (justify left bottom) hide)
      )
      (property "Author" "Antmicro" (at 20.32 -25.4 0)
        (effects (font (size 1.27 1.27) (thickness 0.15)) (justify left bottom) hide)
      )
      (property "Val" "22u" (at 20.32 -7.62 0)
        (effects (font (size 1.27 1.27) (thickness 0.15)) (justify left bottom))
      )
      (property "Voltage" "" (at 20.32 -27.94 0)
        (effects (font (size 1.27 1.27)) (justify left bottom) hide)
      )
      (property "Dielectric" "" (at 20.32 -30.48 0)
        (effects (font (size 1.27 1.27)) (justify left bottom) hide)
      )
      (property "ki_keywords" "0603, SMT, CAPACITOR, PASSIVE, CERAMIC, MLCC" (at 0 0 0)
        (effects (font (size 1.27 1.27)) hide)
      )
      (property "ki_description" "SMD Multilayer Ceramic Capacitor, 22 µF, 6.3 V, 0603 [1608 Metric], ± 20%, X5R, GRM Series" (at 0 0 0)
        (effects (font (size 1.27 1.27)) hide)
      )
      (symbol "C_22u_0603_0_1"
        (polyline
          (pts
            (xy 2.032 -1.524)
            (xy 2.032 1.524)
          )
          (stroke (width 0.3048) (type default))
          (fill (type none))
        )
        (polyline
          (pts
            (xy 3.048 -1.524)
            (xy 3.048 1.524)
          )
          (stroke (width 0.3302) (type default))
          (fill (type none))
        )
      )
      (symbol "C_22u_0603_1_1"
        (pin passive line (at 0 0 0) (length 2.032)
          (name "~" (effects (font (size 1.27 1.27))))
          (number "1" (effects (font (size 1.27 1.27))))
        )
        (pin passive line (at 5.08 0 180) (length 2.032)
          (name "~" (effects (font (size 1.27 1.27))))
          (number "2" (effects (font (size 1.27 1.27))))
        )
      )
    )
	(symbol "antmicroCapacitors0603:C_22u_16V_0603" (pin_numbers hide) (pin_names hide) (in_bom yes) (on_board yes)
      (property "Reference" "C" (at 20.32 -5.08 0)
        (effects (font (size 1.27 1.27) (thickness 0.15)) (justify left bottom))
      )
      (property "Value" "C_22u_16V_0603" (at 20.32 -10.16 0)
        (effects (font (size 1.27 1.27) (thickness 0.15)) (justify left bottom) hide)
      )
      (property "Footprint" "antmicro-footprints:C_0603_1608Metric" (at 20.32 -12.7 0)
        (effects (font (size 1.27 1.27) (thickness 0.15)) (justify left bottom) hide)
      )
      (property "Datasheet" "https://product.samsungsem.com/mlcc/CL10A226MO7JZN.do" (at 20.32 -15.24 0)
        (effects (font (size 1.27 1.27) (thickness 0.15)) (justify left bottom) hide)
      )
      (property "MPN" "CL10A226MO7JZNC" (at 20.32 -17.78 0)
        (effects (font (size 1.27 1.27) (thickness 0.15)) (justify left bottom) hide)
      )
      (property "Manufacturer" "Samsung Electro-Mechanics" (at 20.32 -20.32 0)
        (effects (font (size 1.27 1.27) (thickness 0.15)) (justify left bottom) hide)
      )
      (property "License" "Apache-2.0" (at 20.32 -22.86 0)
        (effects (font (size 1.27 1.27) (thickness 0.15)) (justify left bottom) hide)
      )
      (property "Author" "Antmicro" (at 20.32 -25.4 0)
        (effects (font (size 1.27 1.27) (thickness 0.15)) (justify left bottom) hide)
      )
      (property "Val" "22u" (at 20.32 -7.62 0)
        (effects (font (size 1.27 1.27) (thickness 0.15)) (justify left bottom))
      )
      (property "Voltage" "16V" (at 20.32 -27.94 0)
        (effects (font (size 1.27 1.27)) (justify left bottom) hide)
      )
      (property "Dielectric" "" (at 20.32 -30.48 0)
        (effects (font (size 1.27 1.27)) (justify left bottom) hide)
      )
      (property "ki_keywords" "0603, SMT, CAPACITOR, PASSIVE, CERAMIC" (at 0 0 0)
        (effects (font (size 1.27 1.27)) hide)
      )
      (property "ki_description" "SMD Multilayer Ceramic Capacitor" (at 0 0 0)
        (effects (font (size 1.27 1.27)) hide)
      )
      (symbol "C_22u_16V_0603_0_1"
        (polyline
          (pts
            (xy 2.032 -1.524)
            (xy 2.032 1.524)
          )
          (stroke (width 0.3048) (type default))
          (fill (type none))
        )
        (polyline
          (pts
            (xy 3.048 -1.524)
            (xy 3.048 1.524)
          )
          (stroke (width 0.3302) (type default))
          (fill (type none))
        )
      )
      (symbol "C_22u_16V_0603_1_1"
        (pin passive line (at 0 0 0) (length 2.032)
          (name "~" (effects (font (size 1.27 1.27))))
          (number "1" (effects (font (size 1.27 1.27))))
        )
        (pin passive line (at 5.08 0 180) (length 2.032)
          (name "~" (effects (font (size 1.27 1.27))))
          (number "2" (effects (font (size 1.27 1.27))))
        )
      )
    )
	(symbol "antmicroCapacitorsmisc:C_10u_0805_35V" (pin_numbers hide) (pin_names hide) (in_bom yes) (on_board yes)
      (property "Reference" "C" (at 20.32 -5.08 0)
        (effects (font (size 1.27 1.27) (thickness 0.15)) (justify left bottom))
      )
      (property "Value" "C_10u_0805_35V" (at 20.32 -10.16 0)
        (effects (font (size 1.27 1.27) (thickness 0.15)) (justify left bottom) hide)
      )
      (property "Footprint" "antmicro-footprints:C_0805_2012Metric" (at 20.32 -12.7 0)
        (effects (font (size 1.27 1.27) (thickness 0.15)) (justify left bottom) hide)
      )
      (property "Datasheet" "https://www.murata.com/products/productdetail?partno=GRM21BR6YA106KE43%23" (at 20.32 -15.24 0)
        (effects (font (size 1.27 1.27) (thickness 0.15)) (justify left bottom) hide)
      )
      (property "MPN" "GRM21BR6YA106KE43L" (at 20.32 -17.78 0)
        (effects (font (size 1.27 1.27) (thickness 0.15)) (justify left bottom) hide)
      )
      (property "Manufacturer" "Murata" (at 20.32 -20.32 0)
        (effects (font (size 1.27 1.27) (thickness 0.15)) (justify left bottom) hide)
      )
      (property "License" "Apache-2.0" (at 20.32 -22.86 0)
        (effects (font (size 1.27 1.27) (thickness 0.15)) (justify left bottom) hide)
      )
      (property "Author" "Antmicro" (at 20.32 -25.4 0)
        (effects (font (size 1.27 1.27) (thickness 0.15)) (justify left bottom) hide)
      )
      (property "Val" "10u" (at 20.32 -7.62 0)
        (effects (font (size 1.27 1.27) (thickness 0.15)) (justify left bottom))
      )
      (property "Voltage" "35V" (at 20.32 -27.94 0)
        (effects (font (size 1.27 1.27)) (justify left bottom) hide)
      )
      (property "Dielectric" "" (at 20.32 -30.48 0)
        (effects (font (size 1.27 1.27)) (justify left bottom) hide)
      )
      (property "ki_keywords" "0805, SMT, CAPACITOR, PASSIVE" (at 0 0 0)
        (effects (font (size 1.27 1.27)) hide)
      )
      (property "ki_description" "SMD Multilayer Ceramic Capacitor, 10 µF, 35 V, 0805 [2012 Metric], ± 10%, X5R, GRM Series" (at 0 0 0)
        (effects (font (size 1.27 1.27)) hide)
      )
      (symbol "C_10u_0805_35V_0_1"
        (polyline
          (pts
            (xy 2.032 -1.524)
            (xy 2.032 1.524)
          )
          (stroke (width 0.3048) (type default))
          (fill (type none))
        )
        (polyline
          (pts
            (xy 3.048 -1.524)
            (xy 3.048 1.524)
          )
          (stroke (width 0.3302) (type default))
          (fill (type none))
        )
      )
      (symbol "C_10u_0805_35V_1_1"
        (pin passive line (at 0 0 0) (length 2.032)
          (name "~" (effects (font (size 1.27 1.27))))
          (number "1" (effects (font (size 1.27 1.27))))
        )
        (pin passive line (at 5.08 0 180) (length 2.032)
          (name "~" (effects (font (size 1.27 1.27))))
          (number "2" (effects (font (size 1.27 1.27))))
        )
      )
    )
	(symbol "antmicroCapacitorsmisc:C_22u_1206_35V" (pin_numbers hide) (pin_names hide) (in_bom yes) (on_board yes)
      (property "Reference" "C" (at 20.32 -5.08 0)
        (effects (font (size 1.27 1.27) (thickness 0.15)) (justify left bottom))
      )
      (property "Value" "C_22u_1206_35V" (at 20.32 -10.16 0)
        (effects (font (size 1.27 1.27) (thickness 0.15)) (justify left bottom) hide)
      )
      (property "Footprint" "antmicro-footprints:C_1206_3216Metric" (at 20.32 -12.7 0)
        (effects (font (size 1.27 1.27) (thickness 0.15)) (justify left bottom) hide)
      )
      (property "Datasheet" "https://product.tdk.com/en/search/capacitor/ceramic/mlcc/info?part_no=3216X5R1V226M160AC" (at 20.32 -15.24 0)
        (effects (font (size 1.27 1.27) (thickness 0.15)) (justify left bottom) hide)
      )
      (property "MPN" "3216X5R1V226M160AC" (at 20.32 -17.78 0)
        (effects (font (size 1.27 1.27) (thickness 0.15)) (justify left bottom) hide)
      )
      (property "Manufacturer" "TDK" (at 20.32 -20.32 0)
        (effects (font (size 1.27 1.27) (thickness 0.15)) (justify left bottom) hide)
      )
      (property "License" "Apache-2.0" (at 20.32 -22.86 0)
        (effects (font (size 1.27 1.27) (thickness 0.15)) (justify left bottom) hide)
      )
      (property "Author" "Antmicro" (at 20.32 -25.4 0)
        (effects (font (size 1.27 1.27) (thickness 0.15)) (justify left bottom) hide)
      )
      (property "Val" "22u" (at 20.32 -7.62 0)
        (effects (font (size 1.27 1.27) (thickness 0.15)) (justify left bottom))
      )
      (property "Voltage" "35V" (at 20.32 -27.94 0)
        (effects (font (size 1.27 1.27)) (justify left bottom) hide)
      )
      (property "Dielectric" "" (at 20.32 -30.48 0)
        (effects (font (size 1.27 1.27)) (justify left bottom) hide)
      )
      (property "ki_keywords" "1206, SMT, CAPACITOR, PASSIVE, CERAMIC, MLCC" (at 0 0 0)
        (effects (font (size 1.27 1.27)) hide)
      )
      (property "ki_description" "SMD Multilayer Ceramic Capacitors, 22µF, 35V, X5R, 1206 [2316 Metric], 20% " (at 0 0 0)
        (effects (font (size 1.27 1.27)) hide)
      )
      (symbol "C_22u_1206_35V_0_1"
        (polyline
          (pts
            (xy 2.032 -1.524)
            (xy 2.032 1.524)
          )
          (stroke (width 0.3048) (type default))
          (fill (type none))
        )
        (polyline
          (pts
            (xy 3.048 -1.524)
            (xy 3.048 1.524)
          )
          (stroke (width 0.3302) (type default))
          (fill (type none))
        )
      )
      (symbol "C_22u_1206_35V_1_1"
        (pin passive line (at 0 0 0) (length 2.032)
          (name "~" (effects (font (size 1.27 1.27))))
          (number "1" (effects (font (size 1.27 1.27))))
        )
        (pin passive line (at 5.08 0 180) (length 2.032)
          (name "~" (effects (font (size 1.27 1.27))))
          (number "2" (effects (font (size 1.27 1.27))))
        )
      )
    )
	(symbol "antmicroCapacitorsmisc:C_22u_25V_0805" (pin_numbers hide) (pin_names hide) (in_bom yes) (on_board yes)
      (property "Reference" "C" (at 20.32 -5.08 0)
        (effects (font (size 1.27 1.27) (thickness 0.15)) (justify left bottom))
      )
      (property "Value" "C_22u_25V_0805" (at 20.32 -10.16 0)
        (effects (font (size 1.27 1.27) (thickness 0.15)) (justify left bottom) hide)
      )
      (property "Footprint" "antmicro-footprints:C_0805_2012Metric" (at 20.32 -12.7 0)
        (effects (font (size 1.27 1.27) (thickness 0.15)) (justify left bottom) hide)
      )
      (property "Datasheet" "https://product.samsungsem.com/mlcc/CL21A226MAYNNN.do" (at 20.32 -15.24 0)
        (effects (font (size 1.27 1.27) (thickness 0.15)) (justify left bottom) hide)
      )
      (property "MPN" "CL21A226MAYNNNE" (at 20.32 -17.78 0)
        (effects (font (size 1.27 1.27) (thickness 0.15)) (justify left bottom) hide)
      )
      (property "Manufacturer" "Samsung Electro-Mechanics" (at 20.32 -20.32 0)
        (effects (font (size 1.27 1.27) (thickness 0.15)) (justify left bottom) hide)
      )
      (property "License" "Apache-2.0" (at 20.32 -22.86 0)
        (effects (font (size 1.27 1.27) (thickness 0.15)) (justify left bottom) hide)
      )
      (property "Author" "Antmicro" (at 20.32 -25.4 0)
        (effects (font (size 1.27 1.27) (thickness 0.15)) (justify left bottom) hide)
      )
      (property "Val" "22u" (at 20.32 -7.62 0)
        (effects (font (size 1.27 1.27) (thickness 0.15)) (justify left bottom))
      )
      (property "Voltage" "25V" (at 20.32 -27.94 0)
        (effects (font (size 1.27 1.27)) (justify left bottom))
      )
      (property "Dielectric" "X5R" (at 20.32 -30.48 0)
        (effects (font (size 1.27 1.27)) (justify left bottom) hide)
      )
      (property "ki_keywords" "0805, SMT, CAPACITOR, PASSIVE" (at 0 0 0)
        (effects (font (size 1.27 1.27)) hide)
      )
      (property "ki_description" "SMT Multilayer Ceramic Capacitor, 22uF, +/-20%, 25V, X5R, 0805 [2012 Metric]" (at 0 0 0)
        (effects (font (size 1.27 1.27)) hide)
      )
      (symbol "C_22u_25V_0805_0_1"
        (polyline
          (pts
            (xy 2.032 -1.524)
            (xy 2.032 1.524)
          )
          (stroke (width 0.3048) (type default))
          (fill (type none))
        )
        (polyline
          (pts
            (xy 3.048 -1.524)
            (xy 3.048 1.524)
          )
          (stroke (width 0.3302) (type default))
          (fill (type none))
        )
      )
      (symbol "C_22u_25V_0805_1_1"
        (pin passive line (at 0 0 0) (length 2.032)
          (name "~" (effects (font (size 1.27 1.27))))
          (number "1" (effects (font (size 1.27 1.27))))
        )
        (pin passive line (at 5.08 0 180) (length 2.032)
          (name "~" (effects (font (size 1.27 1.27))))
          (number "2" (effects (font (size 1.27 1.27))))
        )
      )
    )
	(symbol "antmicroClockTimingClockGeneratorsPLLsFrequencySynthesizers:SI52112-B6-GT" (in_bom yes) (on_board yes)
      (property "Reference" "U" (at 38.1 -2.54 0)
        (effects (font (size 1.27 1.27) (thickness 0.15)) (justify left bottom))
      )
      (property "Value" "SI52112-B6-GT" (at 38.1 -5.08 0)
        (effects (font (size 1.27 1.27) (thickness 0.15)) (justify left bottom) hide)
      )
      (property "Footprint" "antmicro-footprints:TSSOP-8_3x4.4mm_P0.65mm" (at 38.1 -7.62 0)
        (effects (font (size 1.27 1.27) (thickness 0.15)) (justify left bottom) hide)
      )
      (property "Datasheet" "https://www.skyworksinc.com/-/media/Skyworks/SL/documents/public/data-sheets/Si52112-B5-B6.pdf" (at 38.1 -10.16 0)
        (effects (font (size 1.27 1.27) (thickness 0.15)) (justify left bottom) hide)
      )
      (property "MPN" "SI52112-B6-GT" (at 38.1 -12.7 0)
        (effects (font (size 1.27 1.27) (thickness 0.15)) (justify left bottom))
      )
      (property "Manufacturer" "Skyworks Solutions" (at 38.1 -15.24 0)
        (effects (font (size 1.27 1.27) (thickness 0.15)) (justify left bottom) hide)
      )
      (property "Author" "Antmicro" (at 38.1 -17.78 0)
        (effects (font (size 1.27 1.27) (thickness 0.15)) (justify left bottom) hide)
      )
      (property "License" "Apache-2.0" (at 38.1 -20.32 0)
        (effects (font (size 1.27 1.27) (thickness 0.15)) (justify left bottom) hide)
      )
      (property "ki_keywords" "IC" (at 0 0 0)
        (effects (font (size 1.27 1.27)) hide)
      )
      (property "ki_description" "Clock Generator, 100MHz, 2.97V to 3.63V, 2 Outputs, TSSOP-8" (at 0 0 0)
        (effects (font (size 1.27 1.27)) hide)
      )
      (symbol "SI52112-B6-GT_0_1"
        (rectangle (start 2.54 2.54) (end 21.59 -10.16)
          (stroke (width 0.254) (type default))
          (fill (type background))
        )
      )
      (symbol "SI52112-B6-GT_1_1"
        (pin power_in line (at 0 0 0) (length 2.54)
          (name "VDD" (effects (font (size 1.27 1.27))))
          (number "1" (effects (font (size 1.27 1.27))))
        )
        (pin output line (at 0 -2.54 0) (length 2.54)
          (name "XOUT" (effects (font (size 1.27 1.27))))
          (number "2" (effects (font (size 1.27 1.27))))
        )
        (pin input line (at 0 -5.08 0) (length 2.54)
          (name "XIN/CLKIN" (effects (font (size 1.27 1.27))))
          (number "3" (effects (font (size 1.27 1.27))))
        )
        (pin power_in line (at 0 -7.62 0) (length 2.54)
          (name "GND" (effects (font (size 1.27 1.27))))
          (number "4" (effects (font (size 1.27 1.27))))
        )
        (pin output line (at 24.13 0 180) (length 2.54)
          (name "DIFF1" (effects (font (size 1.27 1.27))))
          (number "5" (effects (font (size 1.27 1.27))))
        )
        (pin output line (at 24.13 -2.54 180) (length 2.54)
          (name "~{DIFF1}" (effects (font (size 1.27 1.27))))
          (number "6" (effects (font (size 1.27 1.27))))
        )
        (pin output line (at 24.13 -5.08 180) (length 2.54)
          (name "DIFF2" (effects (font (size 1.27 1.27))))
          (number "7" (effects (font (size 1.27 1.27))))
        )
        (pin output line (at 24.13 -7.62 180) (length 2.54)
          (name "~{DIFF2}" (effects (font (size 1.27 1.27))))
          (number "8" (effects (font (size 1.27 1.27))))
        )
      )
    )
	(symbol "antmicroDCDCConverters:LT8350RV" (in_bom yes) (on_board yes)
      (property "Reference" "U" (at 57.15 -5.08 0)
        (effects (font (size 1.27 1.27) (thickness 0.15)) (justify left bottom))
      )
      (property "Value" "LT8350RV" (at 57.15 -10.16 0)
        (effects (font (size 1.27 1.27) (thickness 0.15)) (justify left bottom) hide)
      )
      (property "Footprint" "antmicro-footprints:QFN-32-4EP_4x6mm_P0.5mm" (at 57.15 -12.7 0)
        (effects (font (size 1.27 1.27) (thickness 0.15)) (justify left bottom) hide)
      )
      (property "Datasheet" "https://www.analog.com/media/en/technical-documentation/data-sheets/lt8350.pdf" (at 57.15 -15.24 0)
        (effects (font (size 1.27 1.27) (thickness 0.15)) (justify left bottom) hide)
      )
      (property "MPN" "LT8350RV#PBF" (at 57.15 -7.62 0)
        (effects (font (size 1.27 1.27) (thickness 0.15)) (justify left bottom))
      )
      (property "Manufacturer" "Analog Devices" (at 57.15 -17.78 0)
        (effects (font (size 1.27 1.27) (thickness 0.15)) (justify left bottom) hide)
      )
      (property "License" "Apache-2.0" (at 57.15 -20.32 0)
        (effects (font (size 1.27 1.27) (thickness 0.15)) (justify left bottom) hide)
      )
      (property "Author" "Antmicro" (at 57.15 -22.86 0)
        (effects (font (size 1.27 1.27) (thickness 0.15)) (justify left bottom) hide)
      )
      (property "ki_keywords" "SMT, PMIC, IC, POWER, MANAGEMENT, VOLTAGE, REGULATOR" (at 0 0 0)
        (effects (font (size 1.27 1.27)) hide)
      )
      (property "ki_description" "DC/DC converter" (at 0 0 0)
        (effects (font (size 1.27 1.27)) hide)
      )
      (symbol "LT8350RV_1_1"
        (rectangle (start 2.54 2.54) (end 22.86 -50.8)
          (stroke (width 0.254) (type default))
          (fill (type background))
        )
        (pin output line (at 0 -22.86 0) (length 2.54)
          (name "ISMON" (effects (font (size 1.27 1.27))))
          (number "10" (effects (font (size 1.27 1.27))))
        )
        (pin input line (at 25.4 -17.78 180) (length 2.54)
          (name "ISP" (effects (font (size 1.27 1.27))))
          (number "11" (effects (font (size 1.27 1.27))))
        )
        (pin input line (at 25.4 -20.32 180) (length 2.54)
          (name "ISN" (effects (font (size 1.27 1.27))))
          (number "12" (effects (font (size 1.27 1.27))))
        )
        (pin input line (at 0 -33.02 0) (length 2.54)
          (name "CTRL" (effects (font (size 1.27 1.27))))
          (number "13" (effects (font (size 1.27 1.27))))
        )
        (pin input line (at 25.4 -15.24 180) (length 2.54)
          (name "FB" (effects (font (size 1.27 1.27))))
          (number "14" (effects (font (size 1.27 1.27))))
        )
        (pin output line (at 25.4 -38.1 180) (length 2.54)
          (name "VC" (effects (font (size 1.27 1.27))))
          (number "15" (effects (font (size 1.27 1.27))))
        )
        (pin open_collector line (at 0 -15.24 0) (length 2.54)
          (name "~{PGOOD}" (effects (font (size 1.27 1.27))))
          (number "16" (effects (font (size 1.27 1.27))))
        )
        (pin input line (at 0 -17.78 0) (length 2.54)
          (name "SS" (effects (font (size 1.27 1.27))))
          (number "17" (effects (font (size 1.27 1.27))))
        )
        (pin input line (at 25.4 -40.64 180) (length 2.54)
          (name "RT" (effects (font (size 1.27 1.27))))
          (number "18" (effects (font (size 1.27 1.27))))
        )
        (pin input line (at 0 -48.26 0) (length 2.54)
          (name "SYNC/MODE" (effects (font (size 1.27 1.27))))
          (number "19" (effects (font (size 1.27 1.27))))
        )
        (pin power_in line (at 0 0 0) (length 2.54)
          (name "VIN" (effects (font (size 1.27 1.27))))
          (number "2" (effects (font (size 1.27 1.27))))
        )
        (pin output line (at 0 -27.94 0) (length 2.54)
          (name "CLKOUT" (effects (font (size 1.27 1.27))))
          (number "20" (effects (font (size 1.27 1.27))))
        )
        (pin power_in line (at 25.4 -2.54 180) (length 2.54)
          (name "EXTVCC" (effects (font (size 1.27 1.27))))
          (number "21" (effects (font (size 1.27 1.27))))
        )
        (pin output line (at 0 -25.4 0) (length 2.54)
          (name "LOADTG" (effects (font (size 1.27 1.27))))
          (number "22" (effects (font (size 1.27 1.27))))
        )
        (pin power_out line (at 25.4 0 180) (length 2.54)
          (name "VOUT" (effects (font (size 1.27 1.27))))
          (number "24" (effects (font (size 1.27 1.27))))
        )
        (pin passive line (at 25.4 0 180) (length 2.54) hide
          (name "VOUT" (effects (font (size 1.27 1.27))))
          (number "25" (effects (font (size 1.27 1.27))))
        )
        (pin output line (at 25.4 -30.48 180) (length 2.54)
          (name "SW2" (effects (font (size 1.27 1.27))))
          (number "27" (effects (font (size 1.27 1.27))))
        )
        (pin passive line (at 25.4 -30.48 180) (length 2.54) hide
          (name "SW2" (effects (font (size 1.27 1.27))))
          (number "28" (effects (font (size 1.27 1.27))))
        )
        (pin input line (at 25.4 -33.02 180) (length 2.54)
          (name "BST2" (effects (font (size 1.27 1.27))))
          (number "29" (effects (font (size 1.27 1.27))))
        )
        (pin passive line (at 0 0 0) (length 2.54) hide
          (name "VIN" (effects (font (size 1.27 1.27))))
          (number "3" (effects (font (size 1.27 1.27))))
        )
        (pin input line (at 25.4 -25.4 180) (length 2.54)
          (name "BST1" (effects (font (size 1.27 1.27))))
          (number "30" (effects (font (size 1.27 1.27))))
        )
        (pin output line (at 25.4 -27.94 180) (length 2.54)
          (name "SW1" (effects (font (size 1.27 1.27))))
          (number "31" (effects (font (size 1.27 1.27))))
        )
        (pin passive line (at 25.4 -27.94 180) (length 2.54) hide
          (name "SW1" (effects (font (size 1.27 1.27))))
          (number "32" (effects (font (size 1.27 1.27))))
        )
        (pin power_in line (at 25.4 -48.26 180) (length 2.54)
          (name "GND" (effects (font (size 1.27 1.27))))
          (number "33" (effects (font (size 1.27 1.27))))
        )
        (pin passive line (at 25.4 -48.26 180) (length 2.54) hide
          (name "GND" (effects (font (size 1.27 1.27))))
          (number "34" (effects (font (size 1.27 1.27))))
        )
        (pin passive line (at 25.4 -48.26 180) (length 2.54) hide
          (name "GND" (effects (font (size 1.27 1.27))))
          (number "35" (effects (font (size 1.27 1.27))))
        )
        (pin passive line (at 25.4 -48.26 180) (length 2.54) hide
          (name "GND" (effects (font (size 1.27 1.27))))
          (number "36" (effects (font (size 1.27 1.27))))
        )
        (pin input line (at 0 -2.54 0) (length 2.54)
          (name "EN/UVLO" (effects (font (size 1.27 1.27))))
          (number "5" (effects (font (size 1.27 1.27))))
        )
        (pin power_out line (at 0 -7.62 0) (length 2.54)
          (name "INTVCC" (effects (font (size 1.27 1.27))))
          (number "6" (effects (font (size 1.27 1.27))))
        )
        (pin unspecified line (at 0 -5.08 0) (length 2.54)
          (name "RP" (effects (font (size 1.27 1.27))))
          (number "7" (effects (font (size 1.27 1.27))))
        )
        (pin input line (at 0 -35.56 0) (length 2.54)
          (name "LOADEN" (effects (font (size 1.27 1.27))))
          (number "8" (effects (font (size 1.27 1.27))))
        )
        (pin power_out line (at 0 -38.1 0) (length 2.54)
          (name "VREF" (effects (font (size 1.27 1.27))))
          (number "9" (effects (font (size 1.27 1.27))))
        )
        (pin passive line (at 25.4 -45.72 180) (length 2.54)
          (name "MP" (effects (font (size 1.27 1.27))))
          (number "MP" (effects (font (size 1.27 1.27))))
        )
      )
    )
	(symbol "antmicroDCDCConverters:MP2386GG" (in_bom yes) (on_board yes)
      (property "Reference" "U" (at 33.02 -5.08 0)
        (effects (font (size 1.27 1.27) (thickness 0.15)) (justify left bottom))
      )
      (property "Value" "MP2386GG" (at 33.02 -7.62 0)
        (effects (font (size 1.27 1.27) (thickness 0.15)) (justify left bottom) hide)
      )
      (property "Footprint" "antmicro-footprints:QFN-11_2x2mm_P0.5mm" (at 33.02 -10.16 0)
        (effects (font (size 1.27 1.27) (thickness 0.15)) (justify left bottom) hide)
      )
      (property "Datasheet" "https://www.monolithicpower.com/en/documentview/productdocument/index/version/2/document_type/Datasheet/lang/en/sku/MP2386GG-Z/document_id/4066/" (at 33.02 -12.7 0)
        (effects (font (size 1.27 1.27) (thickness 0.15)) (justify left bottom) hide)
      )
      (property "Manufacturer" "Monolithic Power Systems" (at 33.02 -15.24 0)
        (effects (font (size 1.27 1.27) (thickness 0.15)) (justify left bottom) hide)
      )
      (property "MPN" "MP2386GG-P" (at 33.02 -17.78 0)
        (effects (font (size 1.27 1.27) (thickness 0.15)) (justify left bottom))
      )
      (property "Author" "Antmicro" (at 33.02 -20.32 0)
        (effects (font (size 1.27 1.27) (thickness 0.15)) (justify left bottom) hide)
      )
      (property "License" "Apache-2.0" (at 33.02 -22.86 0)
        (effects (font (size 1.27 1.27) (thickness 0.15)) (justify left bottom) hide)
      )
      (property "ki_keywords" "IC" (at 0 0 0)
        (effects (font (size 1.27 1.27)) hide)
      )
      (property "ki_description" "DC/DC converter" (at 0 0 0)
        (effects (font (size 1.27 1.27)) hide)
      )
      (symbol "MP2386GG_1_1"
        (rectangle (start 2.54 2.54) (end 15.24 -20.32)
          (stroke (width 0.254) (type default))
          (fill (type background))
        )
        (pin power_in line (at 0 0 0) (length 2.54)
          (name "VIN" (effects (font (size 1.27 1.27))))
          (number "1" (effects (font (size 1.27 1.27))))
        )
        (pin input line (at 17.78 -10.16 180) (length 2.54)
          (name "FB" (effects (font (size 1.27 1.27))))
          (number "10" (effects (font (size 1.27 1.27))))
        )
        (pin input line (at 0 -5.08 0) (length 2.54)
          (name "EN" (effects (font (size 1.27 1.27))))
          (number "11" (effects (font (size 1.27 1.27))))
        )
        (pin power_in line (at 0 -17.78 0) (length 2.54)
          (name "PGND" (effects (font (size 1.27 1.27))))
          (number "2" (effects (font (size 1.27 1.27))))
        )
        (pin passive line (at 0 -17.78 0) (length 2.54) hide
          (name "PGND" (effects (font (size 1.27 1.27))))
          (number "3" (effects (font (size 1.27 1.27))))
        )
        (pin passive line (at 0 -17.78 0) (length 2.54) hide
          (name "PGND" (effects (font (size 1.27 1.27))))
          (number "4" (effects (font (size 1.27 1.27))))
        )
        (pin open_collector line (at 17.78 -15.24 180) (length 2.54)
          (name "PG" (effects (font (size 1.27 1.27))))
          (number "5" (effects (font (size 1.27 1.27))))
        )
        (pin power_out line (at 17.78 -2.54 180) (length 2.54)
          (name "SW" (effects (font (size 1.27 1.27))))
          (number "6" (effects (font (size 1.27 1.27))))
        )
        (pin input line (at 17.78 0 180) (length 2.54)
          (name "BST" (effects (font (size 1.27 1.27))))
          (number "7" (effects (font (size 1.27 1.27))))
        )
        (pin power_out line (at 0 -7.62 0) (length 2.54)
          (name "VCC" (effects (font (size 1.27 1.27))))
          (number "8" (effects (font (size 1.27 1.27))))
        )
        (pin power_in line (at 0 -15.24 0) (length 2.54)
          (name "AGND" (effects (font (size 1.27 1.27))))
          (number "9" (effects (font (size 1.27 1.27))))
        )
      )
    )
	(symbol "antmicroDiodesZenerSingle:MM3Z3V3C" (pin_numbers hide) (pin_names hide) (in_bom yes) (on_board yes)
      (property "Reference" "D" (at 22.86 -5.08 0)
        (effects (font (size 1.27 1.27) (thickness 0.15)) (justify left bottom))
      )
      (property "Value" "MM3Z3V3C" (at 22.86 -15.24 0)
        (effects (font (size 1.27 1.27) (thickness 0.15)) (justify left bottom) hide)
      )
      (property "Footprint" "antmicro-footprints:D_SOD-323F" (at 22.86 -10.16 0)
        (effects (font (size 1.27 1.27) (thickness 0.15)) (justify left bottom) hide)
      )
      (property "Datasheet" "https://www.onsemi.com/download/data-sheet/pdf/mm3z9v1c-d.pdf" (at 22.86 -12.7 0)
        (effects (font (size 1.27 1.27) (thickness 0.15)) (justify left bottom) hide)
      )
      (property "MPN" "MM3Z3V3C" (at 22.86 -7.62 0)
        (effects (font (size 1.27 1.27) (thickness 0.15)) (justify left bottom))
      )
      (property "Manufacturer" "ON Semiconductor" (at 22.86 -17.78 0)
        (effects (font (size 1.27 1.27) (thickness 0.15)) (justify left bottom) hide)
      )
      (property "Author" "Antmicro" (at 22.86 -20.32 0)
        (effects (font (size 1.27 1.27) (thickness 0.15)) (justify left bottom) hide)
      )
      (property "License" "Apache-2.0" (at 22.86 -22.86 0)
        (effects (font (size 1.27 1.27) (thickness 0.15)) (justify left bottom) hide)
      )
      (property "ki_keywords" "SMT, DIODE, SEMICONDUCTOR, ZENER" (at 0 0 0)
        (effects (font (size 1.27 1.27)) hide)
      )
      (property "ki_description" "Zener Single Diode, 3.3 V, 200 mW, SOD-323F, 2 Pins, 150 °C, Surface Mount" (at 0 0 0)
        (effects (font (size 1.27 1.27)) hide)
      )
      (symbol "MM3Z3V3C_0_1"
        (polyline
          (pts
            (xy 1.905 0)
            (xy 0.635 0)
          )
          (stroke (width 0) (type default))
          (fill (type none))
        )
        (polyline
          (pts
            (xy 4.445 0)
            (xy 3.175 0)
          )
          (stroke (width 0) (type default))
          (fill (type none))
        )
      )
      (symbol "MM3Z3V3C_1_1"
        (polyline
          (pts
            (xy 1.778 -1.016)
            (xy 1.778 1.016)
          )
          (stroke (width 0.254) (type default))
          (fill (type none))
        )
        (polyline
          (pts
            (xy 2.159 1.016)
            (xy 1.778 1.016)
          )
          (stroke (width 0.254) (type default))
          (fill (type none))
        )
        (polyline
          (pts
            (xy 3.302 -1.016)
            (xy 3.302 1.016)
            (xy 1.778 0)
            (xy 3.302 -1.016)
          )
          (stroke (width 0.254) (type default))
          (fill (type outline))
        )
        (pin passive line (at 0 0 0) (length 0.635)
          (name "C" (effects (font (size 1.27 1.27))))
          (number "1" (effects (font (size 1.27 1.27))))
        )
        (pin passive line (at 5.08 0 180) (length 0.635)
          (name "A" (effects (font (size 1.27 1.27))))
          (number "2" (effects (font (size 1.27 1.27))))
        )
      )
    )
	(symbol "antmicroFerriteBeadsandChips:FB_30Z_8.5A_Murata-BLM21SN_0805" (pin_numbers hide) (pin_names hide) (in_bom yes) (on_board yes)
      (property "Reference" "FB" (at 13.97 0 0)
        (effects (font (size 1.27 1.27) (thickness 0.15)) (justify left bottom))
      )
      (property "Value" "FB_30Z_8.5A_Murata-BLM21SN_0805" (at 13.97 -2.54 0)
        (effects (font (size 1.27 1.27) (thickness 0.15)) (justify left bottom) hide)
      )
      (property "Footprint" "antmicro-footprints:FB_0805_2012Metric" (at 13.97 -7.62 0)
        (effects (font (size 1.27 1.27) (thickness 0.15)) (justify left bottom) hide)
      )
      (property "Datasheet" "https://www.murata.com/en-sg/products/productdata/8796738977822/ENFA0005.pdf?1519270210000" (at 13.97 -10.16 0)
        (effects (font (size 1.27 1.27) (thickness 0.15)) (justify left bottom) hide)
      )
      (property "Val" "30Z/8.5A" (at 13.97 -5.08 0)
        (effects (font (size 1.27 1.27)) (justify left bottom))
      )
      (property "MPN" "BLM21SN300SZ1D" (at 13.97 -12.7 0)
        (effects (font (size 1.27 1.27) (thickness 0.15)) (justify left bottom) hide)
      )
      (property "Manufacturer" "Murata" (at 13.97 -15.24 0)
        (effects (font (size 1.27 1.27) (thickness 0.15)) (justify left bottom) hide)
      )
      (property "Current" "" (at 20.32 -22.86 0)
        (effects (font (size 1.27 1.27) (thickness 0.15)) (justify left bottom) hide)
      )
      (property "Author" "Antmicro" (at 13.97 -17.78 0)
        (effects (font (size 1.27 1.27) (thickness 0.15)) (justify left bottom) hide)
      )
      (property "License" "Apache-2.0" (at 13.97 -20.32 0)
        (effects (font (size 1.27 1.27) (thickness 0.15)) (justify left bottom) hide)
      )
      (property "ki_keywords" "0805, SMT, FERRITE BEAD, PASSIVE" (at 0 0 0)
        (effects (font (size 1.27 1.27)) hide)
      )
      (property "ki_description" "Ferrite Bead, 0805 [2012 Metric], 30 ohm, 8.5 A, BLM21SN, 0.004 ohm, ± 10ohm, DC power line" (at 0 0 0)
        (effects (font (size 1.27 1.27)) hide)
      )
      (symbol "FB_30Z_8.5A_Murata-BLM21SN_0805_0_1"
        (polyline
          (pts
            (xy 1.651 0)
            (xy 1.2446 0)
          )
          (stroke (width 0) (type default))
          (fill (type none))
        )
        (polyline
          (pts
            (xy 3.81 0)
            (xy 3.3274 0)
          )
          (stroke (width 0) (type default))
          (fill (type none))
        )
        (polyline
          (pts
            (xy 2.2606 -1.8288)
            (xy 1.0414 -1.1176)
            (xy 2.7432 1.8288)
            (xy 3.9624 1.1176)
            (xy 2.2606 -1.8288)
          )
          (stroke (width 0) (type default))
          (fill (type none))
        )
      )
      (symbol "FB_30Z_8.5A_Murata-BLM21SN_0805_1_1"
        (pin passive line (at 0 0 0) (length 1.27)
          (name "~" (effects (font (size 1.27 1.27))))
          (number "1" (effects (font (size 1.27 1.27))))
        )
        (pin passive line (at 5.08 0 180) (length 1.27)
          (name "~" (effects (font (size 1.27 1.27))))
          (number "2" (effects (font (size 1.27 1.27))))
        )
      )
    )
	(symbol "antmicroFiducialMarks:Fiducial_1mm_Mask3mm" (in_bom no) (on_board yes)
      (property "Reference" "FD" (at 7.62 0 0)
        (effects (font (size 1.27 1.27) (thickness 0.15)) (justify left bottom))
      )
      (property "Value" "Fiducial_1mm_Mask3mm" (at 7.62 -2.54 0)
        (effects (font (size 1.27 1.27) (thickness 0.15)) (justify left bottom))
      )
      (property "Footprint" "antmicro-footprints:Fiducial_1mm_Mask3mm" (at 7.62 -5.08 0)
        (effects (font (size 1.27 1.27) (thickness 0.15)) (justify left bottom) hide)
      )
      (property "Datasheet" "" (at 7.315 -9.22 0)
        (effects (font (size 1.27 1.27) (thickness 0.15)) (justify left bottom) hide)
      )
      (property "Author" "Antmicro" (at 7.62 -7.62 0)
        (effects (font (size 1.27 1.27) (thickness 0.15)) (justify left bottom) hide)
      )
      (property "License" "Apache-2.0" (at 7.62 -10.16 0)
        (effects (font (size 1.27 1.27) (thickness 0.15)) (justify left bottom) hide)
      )
      (property "ki_description" "Fiducial mask" (at 0 0 0)
        (effects (font (size 1.27 1.27)) hide)
      )
      (symbol "Fiducial_1mm_Mask3mm_1_1"
        (circle (center 0 0) (radius 3.1623)
          (stroke (width 0.254) (type default))
          (fill (type background))
        )
      )
    )
	(symbol "antmicroFixedInductors:L_1u_1.8A_0603" (pin_numbers hide) (pin_names hide) (in_bom yes) (on_board yes)
      (property "Reference" "L" (at 13.97 0 0)
        (effects (font (size 1.27 1.27) (thickness 0.15)) (justify left bottom))
      )
      (property "Value" "L_1u_1.8A_0603" (at 13.97 -2.54 0)
        (effects (font (size 1.27 1.27) (thickness 0.15)) (justify left bottom) hide)
      )
      (property "Footprint" "antmicro-footprints:L_0603_1608Metric" (at 13.97 -7.62 0)
        (effects (font (size 1.27 1.27) (thickness 0.15)) (justify left bottom) hide)
      )
      (property "Datasheet" "https://search.murata.co.jp/Ceramy/image/img/P02/JETE243A-0041.pdf" (at 13.97 -10.16 0)
        (effects (font (size 1.27 1.27) (thickness 0.15)) (justify left bottom) hide)
      )
      (property "Val" "1u/1.8A" (at 13.97 -5.08 0)
        (effects (font (size 1.27 1.27) (thickness 0.15)) (justify left bottom))
      )
      (property "Manufacturer" "Murata" (at 13.97 -12.7 0)
        (effects (font (size 1.27 1.27) (thickness 0.15)) (justify left bottom) hide)
      )
      (property "MPN" "DFE18SBN1R0ME0L" (at 13.97 -15.24 0)
        (effects (font (size 1.27 1.27) (thickness 0.15)) (justify left bottom) hide)
      )
      (property "ISat" "1.9A" (at 13.97 -17.78 0)
        (effects (font (size 1.27 1.27)) (justify left bottom) hide)
      )
      (property "IMax" "1.8A" (at 13.97 -20.32 0)
        (effects (font (size 1.27 1.27) (thickness 0.15)) (justify left bottom) hide)
      )
      (property "Size" "1.6x0.8" (at 13.97 -22.86 0)
        (effects (font (size 1.27 1.27) (thickness 0.15)) (justify left bottom) hide)
      )
      (property "Author" "Antmicro" (at 13.97 -25.4 0)
        (effects (font (size 1.27 1.27) (thickness 0.15)) (justify left bottom) hide)
      )
      (property "License" "Apache-2.0" (at 13.97 -27.94 0)
        (effects (font (size 1.27 1.27) (thickness 0.15)) (justify left bottom) hide)
      )
      (property "ki_keywords" "INDUCTOR, PASSIVE" (at 0 0 0)
        (effects (font (size 1.27 1.27)) hide)
      )
      (property "ki_description" "Power Inductor (SMT), 1 µH, 1.8 A, Shielded, 1.9 A, DFE Series, 0603 [1608 Metric]" (at 0 0 0)
        (effects (font (size 1.27 1.27)) hide)
      )
      (symbol "L_1u_1.8A_0603_0_1"
        (arc (start 1.524 0) (mid 1.016 0.5058) (end 0.508 0)
          (stroke (width 0) (type default))
          (fill (type none))
        )
        (arc (start 2.54 0) (mid 2.032 0.5058) (end 1.524 0)
          (stroke (width 0) (type default))
          (fill (type none))
        )
        (arc (start 3.556 0) (mid 3.048 0.5058) (end 2.54 0)
          (stroke (width 0) (type default))
          (fill (type none))
        )
        (arc (start 4.572 0) (mid 4.064 0.5058) (end 3.556 0)
          (stroke (width 0) (type default))
          (fill (type none))
        )
      )
      (symbol "L_1u_1.8A_0603_1_1"
        (pin passive line (at 0 0 0) (length 0.508)
          (name "~" (effects (font (size 1.27 1.27))))
          (number "1" (effects (font (size 1.27 1.27))))
        )
        (pin passive line (at 5.08 0 180) (length 0.508)
          (name "~" (effects (font (size 1.27 1.27))))
          (number "2" (effects (font (size 1.27 1.27))))
        )
      )
    )
	(symbol "antmicroFixedInductors:L_2u2_9.7A_Coilcraft-XAL5030" (pin_numbers hide) (pin_names hide) (in_bom yes) (on_board yes)
      (property "Reference" "L" (at 13.97 0 0)
        (effects (font (size 1.27 1.27) (thickness 0.15)) (justify left bottom))
      )
      (property "Value" "L_2u2_9.7A_Coilcraft-XAL5030" (at 13.97 -2.54 0)
        (effects (font (size 1.27 1.27) (thickness 0.15)) (justify left bottom) hide)
      )
      (property "Footprint" "antmicro-footprints:L_Coilcraft-XAL5030" (at 13.97 -7.62 0)
        (effects (font (size 1.27 1.27) (thickness 0.15)) (justify left bottom) hide)
      )
      (property "Datasheet" "https://www.coilcraft.com/getmedia/49bc46c8-4b2c-45b9-9b6c-2eaa235ea698/xal50xx.pdf" (at 13.97 -10.16 0)
        (effects (font (size 1.27 1.27) (thickness 0.15)) (justify left bottom) hide)
      )
      (property "Val" "2u2/9.7A" (at 13.97 -5.08 0)
        (effects (font (size 1.27 1.27) (thickness 0.15)) (justify left bottom))
      )
      (property "Manufacturer" "Coilcraft" (at 13.97 -12.7 0)
        (effects (font (size 1.27 1.27) (thickness 0.15)) (justify left bottom) hide)
      )
      (property "MPN" "XAL5030-222MEC" (at 13.97 -15.24 0)
        (effects (font (size 1.27 1.27) (thickness 0.15)) (justify left bottom) hide)
      )
      (property "ISat" "9.2 A" (at 13.97 -16.51 0)
        (effects (font (size 1.27 1.27)) (justify left) hide)
      )
      (property "IMax" "9.7 A" (at 13.97 -20.32 0)
        (effects (font (size 1.27 1.27) (thickness 0.15)) (justify left bottom) hide)
      )
      (property "Size" "5.28x5.48" (at 13.97 -22.86 0)
        (effects (font (size 1.27 1.27) (thickness 0.15)) (justify left bottom) hide)
      )
      (property "Author" "Antmicro" (at 13.97 -25.4 0)
        (effects (font (size 1.27 1.27) (thickness 0.15)) (justify left bottom) hide)
      )
      (property "License" "Apache-2.0" (at 13.97 -27.94 0)
        (effects (font (size 1.27 1.27) (thickness 0.15)) (justify left bottom) hide)
      )
      (property "ki_keywords" "SMT, INDUCTOR, PASSIVE" (at 0 0 0)
        (effects (font (size 1.27 1.27)) hide)
      )
      (property "ki_description" "Power Inductor (SMT), 2.2 µH, 9.7 A, Shielded, 9.2 A, XAL5030" (at 0 0 0)
        (effects (font (size 1.27 1.27)) hide)
      )
      (symbol "L_2u2_9.7A_Coilcraft-XAL5030_0_1"
        (arc (start 1.524 0) (mid 1.016 0.5058) (end 0.508 0)
          (stroke (width 0) (type default))
          (fill (type none))
        )
        (arc (start 2.54 0) (mid 2.032 0.5058) (end 1.524 0)
          (stroke (width 0) (type default))
          (fill (type none))
        )
        (arc (start 3.556 0) (mid 3.048 0.5058) (end 2.54 0)
          (stroke (width 0) (type default))
          (fill (type none))
        )
        (arc (start 4.572 0) (mid 4.064 0.5058) (end 3.556 0)
          (stroke (width 0) (type default))
          (fill (type none))
        )
      )
      (symbol "L_2u2_9.7A_Coilcraft-XAL5030_1_1"
        (pin passive line (at 0 0 0) (length 0.508)
          (name "~" (effects (font (size 1.27 1.27))))
          (number "1" (effects (font (size 1.27 1.27))))
        )
        (pin passive line (at 5.08 0 180) (length 0.508)
          (name "~" (effects (font (size 1.27 1.27))))
          (number "2" (effects (font (size 1.27 1.27))))
        )
      )
    )
	(symbol "antmicroFixedInductors:L_680n_7.6A_IHLP1616BZ" (pin_numbers hide) (pin_names hide) (in_bom yes) (on_board yes)
      (property "Reference" "L" (at 13.97 0 0)
        (effects (font (size 1.27 1.27) (thickness 0.15)) (justify left bottom))
      )
      (property "Value" "L_680n_7.6A_IHLP1616BZ" (at 13.97 -2.54 0)
        (effects (font (size 1.27 1.27) (thickness 0.15)) (justify left bottom) hide)
      )
      (property "Footprint" "antmicro-footprints:L_Vishay-IHLP1616BZ" (at 13.97 -7.62 0)
        (effects (font (size 1.27 1.27) (thickness 0.15)) (justify left bottom) hide)
      )
      (property "Datasheet" "https://www.mouser.com/datasheet/2/427/ihlp1616bz5a-1763007.pdf" (at 13.97 -10.16 0)
        (effects (font (size 1.27 1.27) (thickness 0.15)) (justify left bottom) hide)
      )
      (property "Val" "680n/7.6A" (at 13.97 -5.08 0)
        (effects (font (size 1.27 1.27) (thickness 0.15)) (justify left bottom))
      )
      (property "Manufacturer" "Vishay" (at 13.97 -12.7 0)
        (effects (font (size 1.27 1.27) (thickness 0.15)) (justify left bottom) hide)
      )
      (property "MPN" "IHLP1616BZERR68M5A" (at 13.97 -15.24 0)
        (effects (font (size 1.27 1.27) (thickness 0.15)) (justify left bottom) hide)
      )
      (property "ISat" "6.8 A" (at 13.97 -16.51 0)
        (effects (font (size 1.27 1.27)) (justify left) hide)
      )
      (property "IMax" "7.6 A" (at 13.97 -20.32 0)
        (effects (font (size 1.27 1.27) (thickness 0.15)) (justify left bottom) hide)
      )
      (property "Size" "4.06x4.06" (at 13.97 -22.86 0)
        (effects (font (size 1.27 1.27) (thickness 0.15)) (justify left bottom) hide)
      )
      (property "Author" "Antmicro" (at 13.97 -25.4 0)
        (effects (font (size 1.27 1.27) (thickness 0.15)) (justify left bottom) hide)
      )
      (property "License" "Apache-2.0" (at 13.97 -27.94 0)
        (effects (font (size 1.27 1.27) (thickness 0.15)) (justify left bottom) hide)
      )
      (property "ki_keywords" "SMT, INDUCTOR, PASSIVE" (at 0 0 0)
        (effects (font (size 1.27 1.27)) hide)
      )
      (property "ki_description" "Power Inductor (SMT), 680 nH, 7.6 A, Shielded, 6.8 A, IHLP-1616BZ-5A" (at 0 0 0)
        (effects (font (size 1.27 1.27)) hide)
      )
      (symbol "L_680n_7.6A_IHLP1616BZ_0_1"
        (arc (start 1.524 0) (mid 1.016 0.5058) (end 0.508 0)
          (stroke (width 0) (type default))
          (fill (type none))
        )
        (arc (start 2.54 0) (mid 2.032 0.5058) (end 1.524 0)
          (stroke (width 0) (type default))
          (fill (type none))
        )
        (arc (start 3.556 0) (mid 3.048 0.5058) (end 2.54 0)
          (stroke (width 0) (type default))
          (fill (type none))
        )
        (arc (start 4.572 0) (mid 4.064 0.5058) (end 3.556 0)
          (stroke (width 0) (type default))
          (fill (type none))
        )
      )
      (symbol "L_680n_7.6A_IHLP1616BZ_1_1"
        (pin passive line (at 0 0 0) (length 0.508)
          (name "~" (effects (font (size 1.27 1.27))))
          (number "1" (effects (font (size 1.27 1.27))))
        )
        (pin passive line (at 5.08 0 180) (length 0.508)
          (name "~" (effects (font (size 1.27 1.27))))
          (number "2" (effects (font (size 1.27 1.27))))
        )
      )
    )
	(symbol "antmicroFixedInductors:L_6u8_12.8A_Coilcraft-XAL7070" (pin_numbers hide) (pin_names hide) (in_bom yes) (on_board yes)
      (property "Reference" "L" (at 13.97 0 0)
        (effects (font (size 1.27 1.27) (thickness 0.15)) (justify left bottom))
      )
      (property "Value" "L_6u8_12.8A_Coilcraft-XAL7070" (at 13.97 -2.54 0)
        (effects (font (size 1.27 1.27) (thickness 0.15)) (justify left bottom) hide)
      )
      (property "Footprint" "antmicro-footprints:L_Coilcraft-XAL7070" (at 13.97 -7.62 0)
        (effects (font (size 1.27 1.27) (thickness 0.15)) (justify left bottom) hide)
      )
      (property "Datasheet" "https://www.coilcraft.com/en-us/products/power/shielded-inductors/molded-inductor/xal/xal7070/xal7070-682" (at 13.97 -10.16 0)
        (effects (font (size 1.27 1.27) (thickness 0.15)) (justify left bottom) hide)
      )
      (property "Val" "6u8/12.8A" (at 13.97 -5.08 0)
        (effects (font (size 1.27 1.27) (thickness 0.15)) (justify left bottom))
      )
      (property "Manufacturer" "Coilcraft" (at 13.97 -12.7 0)
        (effects (font (size 1.27 1.27) (thickness 0.15)) (justify left bottom) hide)
      )
      (property "MPN" "XAL7070-682MEC" (at 13.97 -15.24 0)
        (effects (font (size 1.27 1.27) (thickness 0.15)) (justify left bottom) hide)
      )
      (property "ISat" "12.8 A" (at 13.97 -16.51 0)
        (effects (font (size 1.27 1.27)) (justify left) hide)
      )
      (property "IMax" "9.2 A" (at 13.97 -20.32 0)
        (effects (font (size 1.27 1.27) (thickness 0.15)) (justify left bottom) hide)
      )
      (property "Size" "7.7x8" (at 13.97 -22.86 0)
        (effects (font (size 1.27 1.27) (thickness 0.15)) (justify left bottom) hide)
      )
      (property "Author" "Antmicro" (at 13.97 -25.4 0)
        (effects (font (size 1.27 1.27) (thickness 0.15)) (justify left bottom) hide)
      )
      (property "License" "Apache-2.0" (at 13.97 -27.94 0)
        (effects (font (size 1.27 1.27) (thickness 0.15)) (justify left bottom) hide)
      )
      (property "ki_keywords" "SMT, INDUCTOR, PASSIVE" (at 0 0 0)
        (effects (font (size 1.27 1.27)) hide)
      )
      (property "ki_description" "Power Inductor (SMT), 6.8 µH, 9.2 A, Shielded, 12.8 A, XAL7070" (at 0 0 0)
        (effects (font (size 1.27 1.27)) hide)
      )
      (symbol "L_6u8_12.8A_Coilcraft-XAL7070_0_1"
        (arc (start 1.524 0) (mid 1.016 0.5058) (end 0.508 0)
          (stroke (width 0) (type default))
          (fill (type none))
        )
        (arc (start 2.54 0) (mid 2.032 0.5058) (end 1.524 0)
          (stroke (width 0) (type default))
          (fill (type none))
        )
        (arc (start 3.556 0) (mid 3.048 0.5058) (end 2.54 0)
          (stroke (width 0) (type default))
          (fill (type none))
        )
        (arc (start 4.572 0) (mid 4.064 0.5058) (end 3.556 0)
          (stroke (width 0) (type default))
          (fill (type none))
        )
      )
      (symbol "L_6u8_12.8A_Coilcraft-XAL7070_1_1"
        (pin passive line (at 0 0 0) (length 0.508)
          (name "~" (effects (font (size 1.27 1.27))))
          (number "1" (effects (font (size 1.27 1.27))))
        )
        (pin passive line (at 5.08 0 180) (length 0.508)
          (name "~" (effects (font (size 1.27 1.27))))
          (number "2" (effects (font (size 1.27 1.27))))
        )
      )
    )
	(symbol "antmicroInterfaceControllers:JHL6340SLLSQ" (in_bom yes) (on_board yes)
      (property "Reference" "U" (at 71.12 0 0)
        (effects (font (size 1.27 1.27) (thickness 0.15)) (justify left bottom))
      )
      (property "Value" "JHL6340SLLSQ" (at 71.12 -2.54 0)
        (effects (font (size 1.27 1.27) (thickness 0.15)) (justify left bottom) hide)
      )
      (property "Footprint" "antmicro-footprints:JHL6340SLLSQ" (at 71.12 -5.08 0)
        (effects (font (size 1.27 1.27) (thickness 0.15)) (justify left bottom) hide)
      )
      (property "Datasheet" "https://www.thunderbolttechnology.net/sites/default/files/18-241_ThunderboltController_Brief_HI.pdf" (at 71.12 -7.62 0)
        (effects (font (size 1.27 1.27) (thickness 0.15)) (justify left bottom) hide)
      )
      (property "Manufacturer" "Intel" (at 71.12 -10.16 0)
        (effects (font (size 1.27 1.27) (thickness 0.15)) (justify left bottom) hide)
      )
      (property "MPN" "JHL6340SLLSQ" (at 71.12 -12.7 0)
        (effects (font (size 1.27 1.27) (thickness 0.15)) (justify left bottom))
      )
      (property "Author" "Antmicro" (at 71.12 -15.24 0)
        (effects (font (size 1.27 1.27) (thickness 0.15)) (justify left bottom) hide)
      )
      (property "License" "Apache-2.0" (at 71.12 -17.78 0)
        (effects (font (size 1.27 1.27) (thickness 0.15)) (justify left bottom) hide)
      )
      (property "ki_locked" "" (at 0 0 0)
        (effects (font (size 1.27 1.27)))
      )
      (property "ki_keywords" "IC" (at 0 0 0)
        (effects (font (size 1.27 1.27)) hide)
      )
      (property "ki_description" "Thunderbolt™ 3 Controller, I/O" (at 0 0 0)
        (effects (font (size 1.27 1.27)) hide)
      )
      (symbol "JHL6340SLLSQ_1_0"
        (rectangle (start 5.08 3.81) (end 49.53 -85.09)
          (stroke (width 0.254) (type default))
          (fill (type background))
        )
      )
      (symbol "JHL6340SLLSQ_1_1"
        (pin power_in line (at 54.61 -55.88 180) (length 5.08)
          (name "SVR_VSS" (effects (font (size 1.27 1.27))))
          (number "A1" (effects (font (size 1.27 1.27))))
        )
        (pin passive line (at 0 -81.28 0) (length 5.08)
          (name "VSS_ANA" (effects (font (size 1.27 1.27))))
          (number "A10" (effects (font (size 1.27 1.27))))
        )
        (pin passive line (at 0 -81.28 0) (length 5.08) hide
          (name "VSS_ANA" (effects (font (size 1.27 1.27))))
          (number "A12" (effects (font (size 1.27 1.27))))
        )
        (pin passive line (at 0 -81.28 0) (length 5.08) hide
          (name "VSS_ANA" (effects (font (size 1.27 1.27))))
          (number "A14" (effects (font (size 1.27 1.27))))
        )
        (pin passive line (at 0 -81.28 0) (length 5.08) hide
          (name "VSS_ANA" (effects (font (size 1.27 1.27))))
          (number "A16" (effects (font (size 1.27 1.27))))
        )
        (pin passive line (at 0 -81.28 0) (length 5.08) hide
          (name "VSS_ANA" (effects (font (size 1.27 1.27))))
          (number "A18" (effects (font (size 1.27 1.27))))
        )
        (pin power_in line (at 54.61 0 180) (length 5.08)
          (name "VCC3P3_SVR" (effects (font (size 1.27 1.27))))
          (number "A2" (effects (font (size 1.27 1.27))))
        )
        (pin passive line (at 0 -81.28 0) (length 5.08) hide
          (name "VSS_ANA" (effects (font (size 1.27 1.27))))
          (number "A20" (effects (font (size 1.27 1.27))))
        )
        (pin passive line (at 0 -81.28 0) (length 5.08) hide
          (name "VSS_ANA" (effects (font (size 1.27 1.27))))
          (number "A22" (effects (font (size 1.27 1.27))))
        )
        (pin passive line (at 54.61 0 180) (length 5.08) hide
          (name "VCC3P3_SVR" (effects (font (size 1.27 1.27))))
          (number "A3" (effects (font (size 1.27 1.27))))
        )
        (pin passive line (at 0 -81.28 0) (length 5.08) hide
          (name "VSS_ANA" (effects (font (size 1.27 1.27))))
          (number "A6" (effects (font (size 1.27 1.27))))
        )
        (pin passive line (at 0 -81.28 0) (length 5.08) hide
          (name "VSS_ANA" (effects (font (size 1.27 1.27))))
          (number "A8" (effects (font (size 1.27 1.27))))
        )
        (pin passive line (at 0 -81.28 0) (length 5.08) hide
          (name "VSS_ANA" (effects (font (size 1.27 1.27))))
          (number "AA22" (effects (font (size 1.27 1.27))))
        )
        (pin passive line (at 0 -81.28 0) (length 5.08) hide
          (name "VSS_ANA" (effects (font (size 1.27 1.27))))
          (number "AA23" (effects (font (size 1.27 1.27))))
        )
        (pin passive line (at 54.61 -81.28 180) (length 5.08)
          (name "VSS" (effects (font (size 1.27 1.27))))
          (number "AB1" (effects (font (size 1.27 1.27))))
        )
        (pin passive line (at 0 -81.28 0) (length 5.08) hide
          (name "VSS_ANA" (effects (font (size 1.27 1.27))))
          (number "AB10" (effects (font (size 1.27 1.27))))
        )
        (pin passive line (at 0 -81.28 0) (length 5.08) hide
          (name "VSS_ANA" (effects (font (size 1.27 1.27))))
          (number "AB12" (effects (font (size 1.27 1.27))))
        )
        (pin passive line (at 0 -81.28 0) (length 5.08) hide
          (name "VSS_ANA" (effects (font (size 1.27 1.27))))
          (number "AB14" (effects (font (size 1.27 1.27))))
        )
        (pin passive line (at 0 -81.28 0) (length 5.08) hide
          (name "VSS_ANA" (effects (font (size 1.27 1.27))))
          (number "AB16" (effects (font (size 1.27 1.27))))
        )
        (pin passive line (at 0 -81.28 0) (length 5.08) hide
          (name "VSS_ANA" (effects (font (size 1.27 1.27))))
          (number "AB18" (effects (font (size 1.27 1.27))))
        )
        (pin passive line (at 0 -81.28 0) (length 5.08) hide
          (name "VSS_ANA" (effects (font (size 1.27 1.27))))
          (number "AB20" (effects (font (size 1.27 1.27))))
        )
        (pin passive line (at 0 -81.28 0) (length 5.08) hide
          (name "VSS_ANA" (effects (font (size 1.27 1.27))))
          (number "AB22" (effects (font (size 1.27 1.27))))
        )
        (pin passive line (at 0 -81.28 0) (length 5.08) hide
          (name "VSS_ANA" (effects (font (size 1.27 1.27))))
          (number "AB6" (effects (font (size 1.27 1.27))))
        )
        (pin passive line (at 0 -81.28 0) (length 5.08) hide
          (name "VSS_ANA" (effects (font (size 1.27 1.27))))
          (number "AB8" (effects (font (size 1.27 1.27))))
        )
        (pin passive line (at 0 -81.28 0) (length 5.08) hide
          (name "VSS_ANA" (effects (font (size 1.27 1.27))))
          (number "AC10" (effects (font (size 1.27 1.27))))
        )
        (pin passive line (at 0 -81.28 0) (length 5.08) hide
          (name "VSS_ANA" (effects (font (size 1.27 1.27))))
          (number "AC12" (effects (font (size 1.27 1.27))))
        )
        (pin passive line (at 0 -81.28 0) (length 5.08) hide
          (name "VSS_ANA" (effects (font (size 1.27 1.27))))
          (number "AC14" (effects (font (size 1.27 1.27))))
        )
        (pin passive line (at 0 -81.28 0) (length 5.08) hide
          (name "VSS_ANA" (effects (font (size 1.27 1.27))))
          (number "AC16" (effects (font (size 1.27 1.27))))
        )
        (pin passive line (at 0 -81.28 0) (length 5.08) hide
          (name "VSS_ANA" (effects (font (size 1.27 1.27))))
          (number "AC18" (effects (font (size 1.27 1.27))))
        )
        (pin passive line (at 54.61 -81.28 180) (length 5.08) hide
          (name "VSS" (effects (font (size 1.27 1.27))))
          (number "AC2" (effects (font (size 1.27 1.27))))
        )
        (pin passive line (at 0 -81.28 0) (length 5.08) hide
          (name "VSS_ANA" (effects (font (size 1.27 1.27))))
          (number "AC20" (effects (font (size 1.27 1.27))))
        )
        (pin passive line (at 0 -81.28 0) (length 5.08) hide
          (name "VSS_ANA" (effects (font (size 1.27 1.27))))
          (number "AC22" (effects (font (size 1.27 1.27))))
        )
        (pin passive line (at 0 -81.28 0) (length 5.08) hide
          (name "VSS_ANA" (effects (font (size 1.27 1.27))))
          (number "AC6" (effects (font (size 1.27 1.27))))
        )
        (pin passive line (at 0 -81.28 0) (length 5.08) hide
          (name "VSS_ANA" (effects (font (size 1.27 1.27))))
          (number "AC8" (effects (font (size 1.27 1.27))))
        )
        (pin passive line (at 54.61 -55.88 180) (length 5.08) hide
          (name "SVR_VSS" (effects (font (size 1.27 1.27))))
          (number "B1" (effects (font (size 1.27 1.27))))
        )
        (pin passive line (at 0 -81.28 0) (length 5.08) hide
          (name "VSS_ANA" (effects (font (size 1.27 1.27))))
          (number "B10" (effects (font (size 1.27 1.27))))
        )
        (pin passive line (at 0 -81.28 0) (length 5.08) hide
          (name "VSS_ANA" (effects (font (size 1.27 1.27))))
          (number "B12" (effects (font (size 1.27 1.27))))
        )
        (pin passive line (at 0 -81.28 0) (length 5.08) hide
          (name "VSS_ANA" (effects (font (size 1.27 1.27))))
          (number "B14" (effects (font (size 1.27 1.27))))
        )
        (pin passive line (at 0 -81.28 0) (length 5.08) hide
          (name "VSS_ANA" (effects (font (size 1.27 1.27))))
          (number "B16" (effects (font (size 1.27 1.27))))
        )
        (pin passive line (at 0 -81.28 0) (length 5.08) hide
          (name "VSS_ANA" (effects (font (size 1.27 1.27))))
          (number "B18" (effects (font (size 1.27 1.27))))
        )
        (pin passive line (at 54.61 -55.88 180) (length 5.08) hide
          (name "SVR_VSS" (effects (font (size 1.27 1.27))))
          (number "B2" (effects (font (size 1.27 1.27))))
        )
        (pin passive line (at 0 -81.28 0) (length 5.08) hide
          (name "VSS_ANA" (effects (font (size 1.27 1.27))))
          (number "B20" (effects (font (size 1.27 1.27))))
        )
        (pin passive line (at 0 -81.28 0) (length 5.08) hide
          (name "VSS_ANA" (effects (font (size 1.27 1.27))))
          (number "B22" (effects (font (size 1.27 1.27))))
        )
        (pin passive line (at 54.61 0 180) (length 5.08) hide
          (name "VCC3P3_SVR" (effects (font (size 1.27 1.27))))
          (number "B3" (effects (font (size 1.27 1.27))))
        )
        (pin passive line (at 0 -81.28 0) (length 5.08) hide
          (name "VSS_ANA" (effects (font (size 1.27 1.27))))
          (number "B6" (effects (font (size 1.27 1.27))))
        )
        (pin passive line (at 0 -81.28 0) (length 5.08) hide
          (name "VSS_ANA" (effects (font (size 1.27 1.27))))
          (number "B8" (effects (font (size 1.27 1.27))))
        )
        (pin power_out line (at 54.61 -53.34 180) (length 5.08)
          (name "SVR_IND" (effects (font (size 1.27 1.27))))
          (number "C1" (effects (font (size 1.27 1.27))))
        )
        (pin passive line (at 54.61 -53.34 180) (length 5.08) hide
          (name "SVR_IND" (effects (font (size 1.27 1.27))))
          (number "C2" (effects (font (size 1.27 1.27))))
        )
        (pin passive line (at 54.61 -53.34 180) (length 5.08) hide
          (name "SVR_IND" (effects (font (size 1.27 1.27))))
          (number "D1" (effects (font (size 1.27 1.27))))
        )
        (pin passive line (at 0 -81.28 0) (length 5.08) hide
          (name "VSS_ANA" (effects (font (size 1.27 1.27))))
          (number "D11" (effects (font (size 1.27 1.27))))
        )
        (pin passive line (at 0 -81.28 0) (length 5.08) hide
          (name "VSS_ANA" (effects (font (size 1.27 1.27))))
          (number "D12" (effects (font (size 1.27 1.27))))
        )
        (pin passive line (at 0 -81.28 0) (length 5.08) hide
          (name "VSS_ANA" (effects (font (size 1.27 1.27))))
          (number "D13" (effects (font (size 1.27 1.27))))
        )
        (pin passive line (at 0 -81.28 0) (length 5.08) hide
          (name "VSS_ANA" (effects (font (size 1.27 1.27))))
          (number "D15" (effects (font (size 1.27 1.27))))
        )
        (pin passive line (at 0 -81.28 0) (length 5.08) hide
          (name "VSS_ANA" (effects (font (size 1.27 1.27))))
          (number "D16" (effects (font (size 1.27 1.27))))
        )
        (pin passive line (at 0 -81.28 0) (length 5.08) hide
          (name "VSS_ANA" (effects (font (size 1.27 1.27))))
          (number "D18" (effects (font (size 1.27 1.27))))
        )
        (pin passive line (at 54.61 -81.28 180) (length 5.08) hide
          (name "VSS" (effects (font (size 1.27 1.27))))
          (number "D5" (effects (font (size 1.27 1.27))))
        )
        (pin passive line (at 0 -81.28 0) (length 5.08) hide
          (name "VSS_ANA" (effects (font (size 1.27 1.27))))
          (number "D8" (effects (font (size 1.27 1.27))))
        )
        (pin passive line (at 0 -81.28 0) (length 5.08) hide
          (name "VSS_ANA" (effects (font (size 1.27 1.27))))
          (number "D9" (effects (font (size 1.27 1.27))))
        )
        (pin passive line (at 0 -81.28 0) (length 5.08) hide
          (name "VSS_ANA" (effects (font (size 1.27 1.27))))
          (number "E11" (effects (font (size 1.27 1.27))))
        )
        (pin power_in line (at 54.61 -38.1 180) (length 5.08)
          (name "VCC0P9_SVR_ANA" (effects (font (size 1.27 1.27))))
          (number "E12" (effects (font (size 1.27 1.27))))
        )
        (pin passive line (at 54.61 -38.1 180) (length 5.08) hide
          (name "VCC0P9_SVR_ANA" (effects (font (size 1.27 1.27))))
          (number "E13" (effects (font (size 1.27 1.27))))
        )
        (pin passive line (at 0 -81.28 0) (length 5.08) hide
          (name "VSS_ANA" (effects (font (size 1.27 1.27))))
          (number "E15" (effects (font (size 1.27 1.27))))
        )
        (pin passive line (at 0 -81.28 0) (length 5.08) hide
          (name "VSS_ANA" (effects (font (size 1.27 1.27))))
          (number "E16" (effects (font (size 1.27 1.27))))
        )
        (pin passive line (at 0 -81.28 0) (length 5.08) hide
          (name "VSS_ANA" (effects (font (size 1.27 1.27))))
          (number "E22" (effects (font (size 1.27 1.27))))
        )
        (pin passive line (at 0 -81.28 0) (length 5.08) hide
          (name "VSS_ANA" (effects (font (size 1.27 1.27))))
          (number "E23" (effects (font (size 1.27 1.27))))
        )
        (pin passive line (at 54.61 -81.28 180) (length 5.08) hide
          (name "VSS" (effects (font (size 1.27 1.27))))
          (number "E4" (effects (font (size 1.27 1.27))))
        )
        (pin passive line (at 54.61 -81.28 180) (length 5.08) hide
          (name "VSS" (effects (font (size 1.27 1.27))))
          (number "E5" (effects (font (size 1.27 1.27))))
        )
        (pin passive line (at 54.61 -81.28 180) (length 5.08) hide
          (name "VSS" (effects (font (size 1.27 1.27))))
          (number "E6" (effects (font (size 1.27 1.27))))
        )
        (pin passive line (at 0 -81.28 0) (length 5.08) hide
          (name "VSS_ANA" (effects (font (size 1.27 1.27))))
          (number "E8" (effects (font (size 1.27 1.27))))
        )
        (pin passive line (at 0 -81.28 0) (length 5.08) hide
          (name "VSS_ANA" (effects (font (size 1.27 1.27))))
          (number "E9" (effects (font (size 1.27 1.27))))
        )
        (pin passive line (at 54.61 -38.1 180) (length 5.08) hide
          (name "VCC0P9_SVR_ANA" (effects (font (size 1.27 1.27))))
          (number "F11" (effects (font (size 1.27 1.27))))
        )
        (pin passive line (at 54.61 -38.1 180) (length 5.08) hide
          (name "VCC0P9_SVR_ANA" (effects (font (size 1.27 1.27))))
          (number "F12" (effects (font (size 1.27 1.27))))
        )
        (pin passive line (at 54.61 -38.1 180) (length 5.08) hide
          (name "VCC0P9_SVR_ANA" (effects (font (size 1.27 1.27))))
          (number "F13" (effects (font (size 1.27 1.27))))
        )
        (pin passive line (at 54.61 -38.1 180) (length 5.08) hide
          (name "VCC0P9_SVR_ANA" (effects (font (size 1.27 1.27))))
          (number "F15" (effects (font (size 1.27 1.27))))
        )
        (pin passive line (at 0 -81.28 0) (length 5.08) hide
          (name "VSS_ANA" (effects (font (size 1.27 1.27))))
          (number "F16" (effects (font (size 1.27 1.27))))
        )
        (pin power_in line (at 54.61 -71.12 180) (length 5.08)
          (name "VCC0P9_LVR" (effects (font (size 1.27 1.27))))
          (number "F18" (effects (font (size 1.27 1.27))))
        )
        (pin passive line (at 0 -81.28 0) (length 5.08) hide
          (name "VSS_ANA" (effects (font (size 1.27 1.27))))
          (number "F20" (effects (font (size 1.27 1.27))))
        )
        (pin passive line (at 54.61 -81.28 180) (length 5.08) hide
          (name "VSS" (effects (font (size 1.27 1.27))))
          (number "F5" (effects (font (size 1.27 1.27))))
        )
        (pin passive line (at 54.61 -81.28 180) (length 5.08) hide
          (name "VSS" (effects (font (size 1.27 1.27))))
          (number "F6" (effects (font (size 1.27 1.27))))
        )
        (pin power_in line (at 54.61 -2.54 180) (length 5.08)
          (name "VCC3P3_SX" (effects (font (size 1.27 1.27))))
          (number "F8" (effects (font (size 1.27 1.27))))
        )
        (pin passive line (at 0 -81.28 0) (length 5.08) hide
          (name "VSS_ANA" (effects (font (size 1.27 1.27))))
          (number "F9" (effects (font (size 1.27 1.27))))
        )
        (pin passive line (at 0 -81.28 0) (length 5.08) hide
          (name "VSS_ANA" (effects (font (size 1.27 1.27))))
          (number "G22" (effects (font (size 1.27 1.27))))
        )
        (pin passive line (at 0 -81.28 0) (length 5.08) hide
          (name "VSS_ANA" (effects (font (size 1.27 1.27))))
          (number "G23" (effects (font (size 1.27 1.27))))
        )
        (pin passive line (at 0 -81.28 0) (length 5.08) hide
          (name "VSS_ANA" (effects (font (size 1.27 1.27))))
          (number "H1" (effects (font (size 1.27 1.27))))
        )
        (pin power_in line (at 54.61 -73.66 180) (length 5.08)
          (name "VCC0P9_LVR_SENSE" (effects (font (size 1.27 1.27))))
          (number "H11" (effects (font (size 1.27 1.27))))
        )
        (pin passive line (at 0 -81.28 0) (length 5.08) hide
          (name "VSS_ANA" (effects (font (size 1.27 1.27))))
          (number "H12" (effects (font (size 1.27 1.27))))
        )
        (pin passive line (at 0 -81.28 0) (length 5.08) hide
          (name "VSS_ANA" (effects (font (size 1.27 1.27))))
          (number "H13" (effects (font (size 1.27 1.27))))
        )
        (pin passive line (at 0 -81.28 0) (length 5.08) hide
          (name "VSS_ANA" (effects (font (size 1.27 1.27))))
          (number "H15" (effects (font (size 1.27 1.27))))
        )
        (pin passive line (at 0 -81.28 0) (length 5.08) hide
          (name "VSS_ANA" (effects (font (size 1.27 1.27))))
          (number "H16" (effects (font (size 1.27 1.27))))
        )
        (pin passive line (at 54.61 -71.12 180) (length 5.08) hide
          (name "VCC0P9_LVR" (effects (font (size 1.27 1.27))))
          (number "H18" (effects (font (size 1.27 1.27))))
        )
        (pin passive line (at 0 -81.28 0) (length 5.08) hide
          (name "VSS_ANA" (effects (font (size 1.27 1.27))))
          (number "H2" (effects (font (size 1.27 1.27))))
        )
        (pin passive line (at 0 -81.28 0) (length 5.08) hide
          (name "VSS_ANA" (effects (font (size 1.27 1.27))))
          (number "H20" (effects (font (size 1.27 1.27))))
        )
        (pin passive line (at 54.61 -81.28 180) (length 5.08) hide
          (name "VSS" (effects (font (size 1.27 1.27))))
          (number "H5" (effects (font (size 1.27 1.27))))
        )
        (pin passive line (at 54.61 -81.28 180) (length 5.08) hide
          (name "VSS" (effects (font (size 1.27 1.27))))
          (number "H8" (effects (font (size 1.27 1.27))))
        )
        (pin power_in line (at 54.61 -5.08 180) (length 5.08)
          (name "VCC3P3A" (effects (font (size 1.27 1.27))))
          (number "H9" (effects (font (size 1.27 1.27))))
        )
        (pin passive line (at 54.61 -71.12 180) (length 5.08) hide
          (name "VCC0P9_LVR" (effects (font (size 1.27 1.27))))
          (number "J11" (effects (font (size 1.27 1.27))))
        )
        (pin passive line (at 54.61 -81.28 180) (length 5.08) hide
          (name "VSS" (effects (font (size 1.27 1.27))))
          (number "J12" (effects (font (size 1.27 1.27))))
        )
        (pin passive line (at 54.61 -81.28 180) (length 5.08) hide
          (name "VSS" (effects (font (size 1.27 1.27))))
          (number "J13" (effects (font (size 1.27 1.27))))
        )
        (pin passive line (at 54.61 -81.28 180) (length 5.08) hide
          (name "VSS" (effects (font (size 1.27 1.27))))
          (number "J15" (effects (font (size 1.27 1.27))))
        )
        (pin power_in line (at 0 -73.66 0) (length 5.08)
          (name "VCC3P3_ANA_USB2" (effects (font (size 1.27 1.27))))
          (number "J16" (effects (font (size 1.27 1.27))))
        )
        (pin passive line (at 0 -81.28 0) (length 5.08) hide
          (name "VSS_ANA" (effects (font (size 1.27 1.27))))
          (number "J18" (effects (font (size 1.27 1.27))))
        )
        (pin passive line (at 0 -81.28 0) (length 5.08) hide
          (name "VSS_ANA" (effects (font (size 1.27 1.27))))
          (number "J19" (effects (font (size 1.27 1.27))))
        )
        (pin passive line (at 0 -81.28 0) (length 5.08) hide
          (name "VSS_ANA" (effects (font (size 1.27 1.27))))
          (number "J20" (effects (font (size 1.27 1.27))))
        )
        (pin passive line (at 0 -81.28 0) (length 5.08) hide
          (name "VSS_ANA" (effects (font (size 1.27 1.27))))
          (number "J22" (effects (font (size 1.27 1.27))))
        )
        (pin passive line (at 0 -81.28 0) (length 5.08) hide
          (name "VSS_ANA" (effects (font (size 1.27 1.27))))
          (number "J23" (effects (font (size 1.27 1.27))))
        )
        (pin passive line (at 0 -81.28 0) (length 5.08) hide
          (name "VSS_ANA" (effects (font (size 1.27 1.27))))
          (number "J5" (effects (font (size 1.27 1.27))))
        )
        (pin passive line (at 54.61 -81.28 180) (length 5.08) hide
          (name "VSS" (effects (font (size 1.27 1.27))))
          (number "J8" (effects (font (size 1.27 1.27))))
        )
        (pin power_in line (at 54.61 -40.64 180) (length 5.08)
          (name "VCC0P9_SVR_SENSE" (effects (font (size 1.27 1.27))))
          (number "J9" (effects (font (size 1.27 1.27))))
        )
        (pin passive line (at 0 -81.28 0) (length 5.08) hide
          (name "VSS_ANA" (effects (font (size 1.27 1.27))))
          (number "K1" (effects (font (size 1.27 1.27))))
        )
        (pin passive line (at 0 -81.28 0) (length 5.08) hide
          (name "VSS_ANA" (effects (font (size 1.27 1.27))))
          (number "K2" (effects (font (size 1.27 1.27))))
        )
        (pin power_in line (at 0 0 0) (length 5.08)
          (name "VCC0P9_DP" (effects (font (size 1.27 1.27))))
          (number "L11" (effects (font (size 1.27 1.27))))
        )
        (pin passive line (at 0 0 0) (length 5.08) hide
          (name "VCC0P9_DP" (effects (font (size 1.27 1.27))))
          (number "L12" (effects (font (size 1.27 1.27))))
        )
        (pin passive line (at 54.61 -81.28 180) (length 5.08) hide
          (name "VSS" (effects (font (size 1.27 1.27))))
          (number "L13" (effects (font (size 1.27 1.27))))
        )
        (pin power_in line (at 0 -71.12 0) (length 5.08)
          (name "VCC3P3_ANA_PCIE" (effects (font (size 1.27 1.27))))
          (number "L16" (effects (font (size 1.27 1.27))))
        )
        (pin power_in line (at 0 -22.86 0) (length 5.08)
          (name "VCC0P9_ANA_PCIE_2" (effects (font (size 1.27 1.27))))
          (number "L18" (effects (font (size 1.27 1.27))))
        )
        (pin power_in line (at 0 -20.32 0) (length 5.08)
          (name "VCC0P9_ANA_PCIE_1" (effects (font (size 1.27 1.27))))
          (number "L19" (effects (font (size 1.27 1.27))))
        )
        (pin passive line (at 0 -81.28 0) (length 5.08) hide
          (name "VSS_ANA" (effects (font (size 1.27 1.27))))
          (number "L20" (effects (font (size 1.27 1.27))))
        )
        (pin passive line (at 0 -81.28 0) (length 5.08) hide
          (name "VSS_ANA" (effects (font (size 1.27 1.27))))
          (number "L22" (effects (font (size 1.27 1.27))))
        )
        (pin passive line (at 0 -81.28 0) (length 5.08) hide
          (name "VSS_ANA" (effects (font (size 1.27 1.27))))
          (number "L23" (effects (font (size 1.27 1.27))))
        )
        (pin passive line (at 0 -81.28 0) (length 5.08) hide
          (name "VSS_ANA" (effects (font (size 1.27 1.27))))
          (number "L5" (effects (font (size 1.27 1.27))))
        )
        (pin power_in line (at 0 -2.54 0) (length 5.08)
          (name "VCC0P9_ANA_DPSRC" (effects (font (size 1.27 1.27))))
          (number "L6" (effects (font (size 1.27 1.27))))
        )
        (pin passive line (at 0 0 0) (length 5.08) hide
          (name "VCC0P9_DP" (effects (font (size 1.27 1.27))))
          (number "L8" (effects (font (size 1.27 1.27))))
        )
        (pin power_in line (at 54.61 -35.56 180) (length 5.08)
          (name "VCC0P9_SVR" (effects (font (size 1.27 1.27))))
          (number "L9" (effects (font (size 1.27 1.27))))
        )
        (pin passive line (at 0 -81.28 0) (length 5.08) hide
          (name "VSS_ANA" (effects (font (size 1.27 1.27))))
          (number "M1" (effects (font (size 1.27 1.27))))
        )
        (pin passive line (at 54.61 -81.28 180) (length 5.08) hide
          (name "VSS" (effects (font (size 1.27 1.27))))
          (number "M11" (effects (font (size 1.27 1.27))))
        )
        (pin passive line (at 54.61 -81.28 180) (length 5.08) hide
          (name "VSS" (effects (font (size 1.27 1.27))))
          (number "M12" (effects (font (size 1.27 1.27))))
        )
        (pin power_in line (at 0 -17.78 0) (length 5.08)
          (name "VCC0P9_PCIE" (effects (font (size 1.27 1.27))))
          (number "M13" (effects (font (size 1.27 1.27))))
        )
        (pin passive line (at 0 -17.78 0) (length 5.08) hide
          (name "VCC0P9_PCIE" (effects (font (size 1.27 1.27))))
          (number "M15" (effects (font (size 1.27 1.27))))
        )
        (pin passive line (at 0 -17.78 0) (length 5.08) hide
          (name "VCC0P9_PCIE" (effects (font (size 1.27 1.27))))
          (number "M16" (effects (font (size 1.27 1.27))))
        )
        (pin passive line (at 0 -22.86 0) (length 5.08) hide
          (name "VCC0P9_ANA_PCIE_2" (effects (font (size 1.27 1.27))))
          (number "M18" (effects (font (size 1.27 1.27))))
        )
        (pin passive line (at 0 -81.28 0) (length 5.08) hide
          (name "VSS_ANA" (effects (font (size 1.27 1.27))))
          (number "M19" (effects (font (size 1.27 1.27))))
        )
        (pin passive line (at 0 -81.28 0) (length 5.08) hide
          (name "VSS_ANA" (effects (font (size 1.27 1.27))))
          (number "M2" (effects (font (size 1.27 1.27))))
        )
        (pin passive line (at 0 -81.28 0) (length 5.08) hide
          (name "VSS_ANA" (effects (font (size 1.27 1.27))))
          (number "M20" (effects (font (size 1.27 1.27))))
        )
        (pin passive line (at 0 -81.28 0) (length 5.08) hide
          (name "VSS_ANA" (effects (font (size 1.27 1.27))))
          (number "M5" (effects (font (size 1.27 1.27))))
        )
        (pin passive line (at 0 -2.54 0) (length 5.08) hide
          (name "VCC0P9_ANA_DPSRC" (effects (font (size 1.27 1.27))))
          (number "M6" (effects (font (size 1.27 1.27))))
        )
        (pin passive line (at 0 0 0) (length 5.08) hide
          (name "VCC0P9_DP" (effects (font (size 1.27 1.27))))
          (number "M8" (effects (font (size 1.27 1.27))))
        )
        (pin passive line (at 54.61 -35.56 180) (length 5.08) hide
          (name "VCC0P9_SVR" (effects (font (size 1.27 1.27))))
          (number "M9" (effects (font (size 1.27 1.27))))
        )
        (pin passive line (at 54.61 -81.28 180) (length 5.08) hide
          (name "VSS" (effects (font (size 1.27 1.27))))
          (number "N11" (effects (font (size 1.27 1.27))))
        )
        (pin passive line (at 54.61 -81.28 180) (length 5.08) hide
          (name "VSS" (effects (font (size 1.27 1.27))))
          (number "N12" (effects (font (size 1.27 1.27))))
        )
        (pin passive line (at 54.61 -81.28 180) (length 5.08) hide
          (name "VSS" (effects (font (size 1.27 1.27))))
          (number "N13" (effects (font (size 1.27 1.27))))
        )
        (pin passive line (at 0 -22.86 0) (length 5.08) hide
          (name "VCC0P9_ANA_PCIE_2" (effects (font (size 1.27 1.27))))
          (number "N18" (effects (font (size 1.27 1.27))))
        )
        (pin passive line (at 0 -20.32 0) (length 5.08) hide
          (name "VCC0P9_ANA_PCIE_1" (effects (font (size 1.27 1.27))))
          (number "N19" (effects (font (size 1.27 1.27))))
        )
        (pin passive line (at 0 -81.28 0) (length 5.08) hide
          (name "VSS_ANA" (effects (font (size 1.27 1.27))))
          (number "N20" (effects (font (size 1.27 1.27))))
        )
        (pin passive line (at 0 -81.28 0) (length 5.08) hide
          (name "VSS_ANA" (effects (font (size 1.27 1.27))))
          (number "N22" (effects (font (size 1.27 1.27))))
        )
        (pin passive line (at 0 -81.28 0) (length 5.08) hide
          (name "VSS_ANA" (effects (font (size 1.27 1.27))))
          (number "N23" (effects (font (size 1.27 1.27))))
        )
        (pin passive line (at 0 -81.28 0) (length 5.08) hide
          (name "VSS_ANA" (effects (font (size 1.27 1.27))))
          (number "N5" (effects (font (size 1.27 1.27))))
        )
        (pin passive line (at 54.61 -81.28 180) (length 5.08) hide
          (name "VSS" (effects (font (size 1.27 1.27))))
          (number "N8" (effects (font (size 1.27 1.27))))
        )
        (pin passive line (at 54.61 -81.28 180) (length 5.08) hide
          (name "VSS" (effects (font (size 1.27 1.27))))
          (number "N9" (effects (font (size 1.27 1.27))))
        )
        (pin passive line (at 0 -81.28 0) (length 5.08) hide
          (name "VSS_ANA" (effects (font (size 1.27 1.27))))
          (number "P1" (effects (font (size 1.27 1.27))))
        )
        (pin passive line (at 0 -81.28 0) (length 5.08) hide
          (name "VSS_ANA" (effects (font (size 1.27 1.27))))
          (number "P2" (effects (font (size 1.27 1.27))))
        )
        (pin power_in line (at 0 -53.34 0) (length 5.08)
          (name "VCC0P9_CIO" (effects (font (size 1.27 1.27))))
          (number "R11" (effects (font (size 1.27 1.27))))
        )
        (pin passive line (at 0 -53.34 0) (length 5.08) hide
          (name "VCC0P9_CIO" (effects (font (size 1.27 1.27))))
          (number "R12" (effects (font (size 1.27 1.27))))
        )
        (pin power_in line (at 54.61 -17.78 180) (length 5.08)
          (name "VCC3P3_S0" (effects (font (size 1.27 1.27))))
          (number "R13" (effects (font (size 1.27 1.27))))
        )
        (pin power_in line (at 0 -35.56 0) (length 5.08)
          (name "VCC0P9_USB" (effects (font (size 1.27 1.27))))
          (number "R15" (effects (font (size 1.27 1.27))))
        )
        (pin passive line (at 0 -35.56 0) (length 5.08) hide
          (name "VCC0P9_USB" (effects (font (size 1.27 1.27))))
          (number "R16" (effects (font (size 1.27 1.27))))
        )
        (pin passive line (at 0 -81.28 0) (length 5.08) hide
          (name "VSS_ANA" (effects (font (size 1.27 1.27))))
          (number "R18" (effects (font (size 1.27 1.27))))
        )
        (pin passive line (at 0 -81.28 0) (length 5.08) hide
          (name "VSS_ANA" (effects (font (size 1.27 1.27))))
          (number "R19" (effects (font (size 1.27 1.27))))
        )
        (pin passive line (at 0 -81.28 0) (length 5.08) hide
          (name "VSS_ANA" (effects (font (size 1.27 1.27))))
          (number "R20" (effects (font (size 1.27 1.27))))
        )
        (pin passive line (at 0 -81.28 0) (length 5.08) hide
          (name "VSS_ANA" (effects (font (size 1.27 1.27))))
          (number "R22" (effects (font (size 1.27 1.27))))
        )
        (pin passive line (at 0 -81.28 0) (length 5.08) hide
          (name "VSS_ANA" (effects (font (size 1.27 1.27))))
          (number "R23" (effects (font (size 1.27 1.27))))
        )
        (pin passive line (at 0 -81.28 0) (length 5.08) hide
          (name "VSS_ANA" (effects (font (size 1.27 1.27))))
          (number "R5" (effects (font (size 1.27 1.27))))
        )
        (pin power_in line (at 54.61 -20.32 180) (length 5.08)
          (name "VCC3P3_LC" (effects (font (size 1.27 1.27))))
          (number "R6" (effects (font (size 1.27 1.27))))
        )
        (pin passive line (at 0 -53.34 0) (length 5.08) hide
          (name "VCC0P9_CIO" (effects (font (size 1.27 1.27))))
          (number "R8" (effects (font (size 1.27 1.27))))
        )
        (pin passive line (at 0 -53.34 0) (length 5.08) hide
          (name "VCC0P9_CIO" (effects (font (size 1.27 1.27))))
          (number "R9" (effects (font (size 1.27 1.27))))
        )
        (pin passive line (at 0 -81.28 0) (length 5.08) hide
          (name "VSS_ANA" (effects (font (size 1.27 1.27))))
          (number "T1" (effects (font (size 1.27 1.27))))
        )
        (pin passive line (at 0 0 0) (length 5.08) hide
          (name "VCC0P9_DP" (effects (font (size 1.27 1.27))))
          (number "T11" (effects (font (size 1.27 1.27))))
        )
        (pin passive line (at 0 0 0) (length 5.08) hide
          (name "VCC0P9_DP" (effects (font (size 1.27 1.27))))
          (number "T12" (effects (font (size 1.27 1.27))))
        )
        (pin passive line (at 54.61 -81.28 180) (length 5.08) hide
          (name "VSS" (effects (font (size 1.27 1.27))))
          (number "T13" (effects (font (size 1.27 1.27))))
        )
        (pin passive line (at 54.61 -81.28 180) (length 5.08) hide
          (name "VSS" (effects (font (size 1.27 1.27))))
          (number "T15" (effects (font (size 1.27 1.27))))
        )
        (pin passive line (at 54.61 -81.28 180) (length 5.08) hide
          (name "VSS" (effects (font (size 1.27 1.27))))
          (number "T16" (effects (font (size 1.27 1.27))))
        )
        (pin passive line (at 54.61 -81.28 180) (length 5.08) hide
          (name "VSS" (effects (font (size 1.27 1.27))))
          (number "T18" (effects (font (size 1.27 1.27))))
        )
        (pin passive line (at 0 -81.28 0) (length 5.08) hide
          (name "VSS_ANA" (effects (font (size 1.27 1.27))))
          (number "T2" (effects (font (size 1.27 1.27))))
        )
        (pin passive line (at 0 -81.28 0) (length 5.08) hide
          (name "VSS_ANA" (effects (font (size 1.27 1.27))))
          (number "T20" (effects (font (size 1.27 1.27))))
        )
        (pin passive line (at 0 -81.28 0) (length 5.08) hide
          (name "VSS_ANA" (effects (font (size 1.27 1.27))))
          (number "T5" (effects (font (size 1.27 1.27))))
        )
        (pin passive line (at 54.61 -81.28 180) (length 5.08) hide
          (name "VSS" (effects (font (size 1.27 1.27))))
          (number "T6" (effects (font (size 1.27 1.27))))
        )
        (pin passive line (at 54.61 -81.28 180) (length 5.08) hide
          (name "VSS" (effects (font (size 1.27 1.27))))
          (number "T8" (effects (font (size 1.27 1.27))))
        )
        (pin passive line (at 54.61 -81.28 180) (length 5.08) hide
          (name "VSS" (effects (font (size 1.27 1.27))))
          (number "T9" (effects (font (size 1.27 1.27))))
        )
        (pin passive line (at 0 -81.28 0) (length 5.08) hide
          (name "VSS_ANA" (effects (font (size 1.27 1.27))))
          (number "U22" (effects (font (size 1.27 1.27))))
        )
        (pin passive line (at 0 -81.28 0) (length 5.08) hide
          (name "VSS_ANA" (effects (font (size 1.27 1.27))))
          (number "U23" (effects (font (size 1.27 1.27))))
        )
        (pin power_in line (at 0 -5.08 0) (length 5.08)
          (name "VCC0P9_ANA_DPSNK" (effects (font (size 1.27 1.27))))
          (number "V11" (effects (font (size 1.27 1.27))))
        )
        (pin passive line (at 0 -5.08 0) (length 5.08) hide
          (name "VCC0P9_ANA_DPSNK" (effects (font (size 1.27 1.27))))
          (number "V12" (effects (font (size 1.27 1.27))))
        )
        (pin passive line (at 0 -5.08 0) (length 5.08) hide
          (name "VCC0P9_ANA_DPSNK" (effects (font (size 1.27 1.27))))
          (number "V13" (effects (font (size 1.27 1.27))))
        )
        (pin passive line (at 0 -81.28 0) (length 5.08) hide
          (name "VSS_ANA" (effects (font (size 1.27 1.27))))
          (number "V15" (effects (font (size 1.27 1.27))))
        )
        (pin passive line (at 0 -81.28 0) (length 5.08) hide
          (name "VSS_ANA" (effects (font (size 1.27 1.27))))
          (number "V16" (effects (font (size 1.27 1.27))))
        )
        (pin passive line (at 0 -81.28 0) (length 5.08) hide
          (name "VSS_ANA" (effects (font (size 1.27 1.27))))
          (number "V20" (effects (font (size 1.27 1.27))))
        )
        (pin passive line (at 0 -81.28 0) (length 5.08) hide
          (name "VSS_ANA" (effects (font (size 1.27 1.27))))
          (number "V5" (effects (font (size 1.27 1.27))))
        )
        (pin passive line (at 0 -81.28 0) (length 5.08) hide
          (name "VSS_ANA" (effects (font (size 1.27 1.27))))
          (number "V6" (effects (font (size 1.27 1.27))))
        )
        (pin passive line (at 0 -81.28 0) (length 5.08) hide
          (name "VSS_ANA" (effects (font (size 1.27 1.27))))
          (number "V8" (effects (font (size 1.27 1.27))))
        )
        (pin passive line (at 0 -81.28 0) (length 5.08) hide
          (name "VSS_ANA" (effects (font (size 1.27 1.27))))
          (number "V9" (effects (font (size 1.27 1.27))))
        )
        (pin passive line (at 0 -81.28 0) (length 5.08) hide
          (name "VSS_ANA" (effects (font (size 1.27 1.27))))
          (number "W20" (effects (font (size 1.27 1.27))))
        )
        (pin passive line (at 0 -81.28 0) (length 5.08) hide
          (name "VSS_ANA" (effects (font (size 1.27 1.27))))
          (number "W22" (effects (font (size 1.27 1.27))))
        )
        (pin passive line (at 0 -81.28 0) (length 5.08) hide
          (name "VSS_ANA" (effects (font (size 1.27 1.27))))
          (number "W23" (effects (font (size 1.27 1.27))))
        )
        (pin passive line (at 0 -81.28 0) (length 5.08) hide
          (name "VSS_ANA" (effects (font (size 1.27 1.27))))
          (number "W5" (effects (font (size 1.27 1.27))))
        )
        (pin passive line (at 0 -81.28 0) (length 5.08) hide
          (name "VSS_ANA" (effects (font (size 1.27 1.27))))
          (number "W6" (effects (font (size 1.27 1.27))))
        )
        (pin passive line (at 0 -81.28 0) (length 5.08) hide
          (name "VSS_ANA" (effects (font (size 1.27 1.27))))
          (number "W8" (effects (font (size 1.27 1.27))))
        )
        (pin passive line (at 0 -81.28 0) (length 5.08) hide
          (name "VSS_ANA" (effects (font (size 1.27 1.27))))
          (number "W9" (effects (font (size 1.27 1.27))))
        )
        (pin passive line (at 0 -81.28 0) (length 5.08) hide
          (name "VSS_ANA" (effects (font (size 1.27 1.27))))
          (number "Y13" (effects (font (size 1.27 1.27))))
        )
        (pin passive line (at 0 -81.28 0) (length 5.08) hide
          (name "VSS_ANA" (effects (font (size 1.27 1.27))))
          (number "Y20" (effects (font (size 1.27 1.27))))
        )
        (pin passive line (at 0 -81.28 0) (length 5.08) hide
          (name "VSS_ANA" (effects (font (size 1.27 1.27))))
          (number "Y9" (effects (font (size 1.27 1.27))))
        )
      )
      (symbol "JHL6340SLLSQ_2_0"
        (text "PCIe Gen3" (at 24.13 -17.78 0)
          (effects (font (size 1.27 1.27) (thickness 0.15)) (justify left bottom))
        )
      )
      (symbol "JHL6340SLLSQ_2_1"
        (rectangle (start 5.08 5.08) (end 50.8 -40.64)
          (stroke (width 0.254) (type default))
          (fill (type background))
        )
        (pin output line (at 0 -38.1 0) (length 5.08)
          (name "PCIE_CLKREQ_N" (effects (font (size 1.27 1.27))))
          (number "AC5" (effects (font (size 1.27 1.27))))
        )
        (pin input line (at 55.88 -25.4 180) (length 5.08)
          (name "PCIE_TX3_N" (effects (font (size 1.27 1.27))))
          (number "F22" (effects (font (size 1.27 1.27))))
        )
        (pin input line (at 55.88 -22.86 180) (length 5.08)
          (name "PCIE_TX3_P" (effects (font (size 1.27 1.27))))
          (number "F23" (effects (font (size 1.27 1.27))))
        )
        (pin input line (at 0 -25.4 0) (length 5.08)
          (name "PCIE_RX3_N" (effects (font (size 1.27 1.27))))
          (number "H22" (effects (font (size 1.27 1.27))))
        )
        (pin input line (at 0 -22.86 0) (length 5.08)
          (name "PCIE_RX3_P" (effects (font (size 1.27 1.27))))
          (number "H23" (effects (font (size 1.27 1.27))))
        )
        (pin input line (at 55.88 -17.78 180) (length 5.08)
          (name "PCIE_TX2_N" (effects (font (size 1.27 1.27))))
          (number "K22" (effects (font (size 1.27 1.27))))
        )
        (pin input line (at 55.88 -15.24 180) (length 5.08)
          (name "PCIE_TX2_P" (effects (font (size 1.27 1.27))))
          (number "K23" (effects (font (size 1.27 1.27))))
        )
        (pin input line (at 55.88 -33.02 180) (length 5.08)
          (name "PERST_N" (effects (font (size 1.27 1.27))))
          (number "L4" (effects (font (size 1.27 1.27))))
        )
        (pin input line (at 0 -17.78 0) (length 5.08)
          (name "PCIE_RX2_N" (effects (font (size 1.27 1.27))))
          (number "M22" (effects (font (size 1.27 1.27))))
        )
        (pin input line (at 0 -15.24 0) (length 5.08)
          (name "PCIE_RX2_P" (effects (font (size 1.27 1.27))))
          (number "M23" (effects (font (size 1.27 1.27))))
        )
        (pin input line (at 55.88 -38.1 180) (length 5.08)
          (name "PCIE_RBIAS" (effects (font (size 1.27 1.27))))
          (number "N16" (effects (font (size 1.27 1.27))))
        )
        (pin input line (at 55.88 -10.16 180) (length 5.08)
          (name "PCIE_TX1_N" (effects (font (size 1.27 1.27))))
          (number "P22" (effects (font (size 1.27 1.27))))
        )
        (pin input line (at 55.88 -7.62 180) (length 5.08)
          (name "PCIE_TX1_P" (effects (font (size 1.27 1.27))))
          (number "P23" (effects (font (size 1.27 1.27))))
        )
        (pin input line (at 0 -33.02 0) (length 5.08)
          (name "PCIE_REFCLK_100_IN_N" (effects (font (size 1.27 1.27))))
          (number "T19" (effects (font (size 1.27 1.27))))
        )
        (pin input line (at 0 -10.16 0) (length 5.08)
          (name "PCIE_RX1_N" (effects (font (size 1.27 1.27))))
          (number "T22" (effects (font (size 1.27 1.27))))
        )
        (pin input line (at 0 -7.62 0) (length 5.08)
          (name "PCIE_RX1_P" (effects (font (size 1.27 1.27))))
          (number "T23" (effects (font (size 1.27 1.27))))
        )
        (pin input line (at 0 -30.48 0) (length 5.08)
          (name "PCIE_REFCLK_100_IN_P" (effects (font (size 1.27 1.27))))
          (number "V19" (effects (font (size 1.27 1.27))))
        )
        (pin input line (at 55.88 -2.54 180) (length 5.08)
          (name "PCIE_TX0_N" (effects (font (size 1.27 1.27))))
          (number "V22" (effects (font (size 1.27 1.27))))
        )
        (pin input line (at 55.88 0 180) (length 5.08)
          (name "PCIE_TX0_P" (effects (font (size 1.27 1.27))))
          (number "V23" (effects (font (size 1.27 1.27))))
        )
        (pin input line (at 0 -2.54 0) (length 5.08)
          (name "PCIE_RX0_N" (effects (font (size 1.27 1.27))))
          (number "Y22" (effects (font (size 1.27 1.27))))
        )
        (pin input line (at 0 0 0) (length 5.08)
          (name "PCIE_RX0_P" (effects (font (size 1.27 1.27))))
          (number "Y23" (effects (font (size 1.27 1.27))))
        )
      )
      (symbol "JHL6340SLLSQ_3_0"
        (polyline
          (pts
            (xy 15.24 -50.8)
            (xy 24.13 -50.8)
            (xy 24.13 -101.6)
            (xy 15.24 -101.6)
          )
          (stroke (width 0) (type default))
          (fill (type none))
        )
        (polyline
          (pts
            (xy 15.24 2.54)
            (xy 24.13 2.54)
            (xy 24.13 -48.26)
            (xy 15.24 -48.26)
          )
          (stroke (width 0) (type default))
          (fill (type none))
        )
        (polyline
          (pts
            (xy 40.64 -76.2)
            (xy 31.75 -76.2)
            (xy 31.75 -96.52)
            (xy 40.64 -96.52)
          )
          (stroke (width 0) (type default))
          (fill (type none))
        )
        (polyline
          (pts
            (xy 40.64 -48.26)
            (xy 31.75 -48.26)
            (xy 31.75 -73.66)
            (xy 40.64 -73.66)
          )
          (stroke (width 0) (type default))
          (fill (type none))
        )
        (polyline
          (pts
            (xy 40.64 2.54)
            (xy 31.75 2.54)
            (xy 31.75 -45.72)
            (xy 40.64 -45.72)
          )
          (stroke (width 0) (type default))
          (fill (type none))
        )
        (text "GPIO" (at 30.48 -60.96 900)
          (effects (font (size 1.27 1.27) (thickness 0.15)) (justify left bottom))
        )
        (text "POC_GPIO" (at 30.48 -90.17 900)
          (effects (font (size 1.27 1.27) (thickness 0.15)) (justify left bottom))
        )
        (text "SINK PORT 0" (at 26.67 -27.94 900)
          (effects (font (size 1.27 1.27) (thickness 0.15)) (justify left bottom))
        )
        (text "SINK PORT 1" (at 26.67 -80.01 900)
          (effects (font (size 1.27 1.27) (thickness 0.15)) (justify left bottom))
        )
        (text "SOURCE PORT 0" (at 30.48 -29.21 900)
          (effects (font (size 1.27 1.27) (thickness 0.15)) (justify left bottom))
        )
      )
      (symbol "JHL6340SLLSQ_3_1"
        (rectangle (start 5.08 3.81) (end 50.8 -107.95)
          (stroke (width 0.254) (type default))
          (fill (type background))
        )
        (pin bidirectional line (at 55.88 -71.12 180) (length 5.08)
          (name "GPIO_8" (effects (font (size 1.27 1.27))))
          (number "AA1" (effects (font (size 1.27 1.27))))
        )
        (pin passive line (at 0 -38.1 0) (length 5.08)
          (name "DPSNK0_HPD" (effects (font (size 1.27 1.27))))
          (number "AA2" (effects (font (size 1.27 1.27))))
        )
        (pin input line (at 0 -15.24 0) (length 5.08)
          (name "DPSNK0_ML2_P" (effects (font (size 1.27 1.27))))
          (number "AB11" (effects (font (size 1.27 1.27))))
        )
        (pin input line (at 0 -22.86 0) (length 5.08)
          (name "DPSNK0_ML3_P" (effects (font (size 1.27 1.27))))
          (number "AB13" (effects (font (size 1.27 1.27))))
        )
        (pin input line (at 0 -53.34 0) (length 5.08)
          (name "DPSNK1_ML0_P" (effects (font (size 1.27 1.27))))
          (number "AB15" (effects (font (size 1.27 1.27))))
        )
        (pin input line (at 0 -60.96 0) (length 5.08)
          (name "DPSNK1_ML1_P" (effects (font (size 1.27 1.27))))
          (number "AB17" (effects (font (size 1.27 1.27))))
        )
        (pin input line (at 0 -68.58 0) (length 5.08)
          (name "DPSNK1_ML2_P" (effects (font (size 1.27 1.27))))
          (number "AB19" (effects (font (size 1.27 1.27))))
        )
        (pin input line (at 0 -76.2 0) (length 5.08)
          (name "DPSNK1_ML3_P" (effects (font (size 1.27 1.27))))
          (number "AB21" (effects (font (size 1.27 1.27))))
        )
        (pin input line (at 0 0 0) (length 5.08)
          (name "DPSNK0_ML0_P" (effects (font (size 1.27 1.27))))
          (number "AB7" (effects (font (size 1.27 1.27))))
        )
        (pin input line (at 0 -7.62 0) (length 5.08)
          (name "DPSNK0_ML1_P" (effects (font (size 1.27 1.27))))
          (number "AB9" (effects (font (size 1.27 1.27))))
        )
        (pin input line (at 0 -17.78 0) (length 5.08)
          (name "DPSNK0_ML2_N" (effects (font (size 1.27 1.27))))
          (number "AC11" (effects (font (size 1.27 1.27))))
        )
        (pin input line (at 0 -25.4 0) (length 5.08)
          (name "DPSNK0_ML3_N" (effects (font (size 1.27 1.27))))
          (number "AC13" (effects (font (size 1.27 1.27))))
        )
        (pin input line (at 0 -55.88 0) (length 5.08)
          (name "DPSNK1_ML0_N" (effects (font (size 1.27 1.27))))
          (number "AC15" (effects (font (size 1.27 1.27))))
        )
        (pin input line (at 0 -63.5 0) (length 5.08)
          (name "DPSNK1_ML1_N" (effects (font (size 1.27 1.27))))
          (number "AC17" (effects (font (size 1.27 1.27))))
        )
        (pin input line (at 0 -71.12 0) (length 5.08)
          (name "DPSNK1_ML2_N" (effects (font (size 1.27 1.27))))
          (number "AC19" (effects (font (size 1.27 1.27))))
        )
        (pin input line (at 0 -78.74 0) (length 5.08)
          (name "DPSNK1_ML3_N" (effects (font (size 1.27 1.27))))
          (number "AC21" (effects (font (size 1.27 1.27))))
        )
        (pin input line (at 0 -2.54 0) (length 5.08)
          (name "DPSNK0_ML0_N" (effects (font (size 1.27 1.27))))
          (number "AC7" (effects (font (size 1.27 1.27))))
        )
        (pin input line (at 0 -10.16 0) (length 5.08)
          (name "DPSNK0_ML1_N" (effects (font (size 1.27 1.27))))
          (number "AC9" (effects (font (size 1.27 1.27))))
        )
        (pin bidirectional line (at 55.88 -91.44 180) (length 5.08)
          (name "POC_GPIO_5" (effects (font (size 1.27 1.27))))
          (number "D2" (effects (font (size 1.27 1.27))))
        )
        (pin bidirectional line (at 55.88 -83.82 180) (length 5.08)
          (name "POC_GPIO_2" (effects (font (size 1.27 1.27))))
          (number "D4" (effects (font (size 1.27 1.27))))
        )
        (pin bidirectional line (at 55.88 -81.28 180) (length 5.08)
          (name "POC_GPIO_1" (effects (font (size 1.27 1.27))))
          (number "E2" (effects (font (size 1.27 1.27))))
        )
        (pin bidirectional line (at 55.88 -93.98 180) (length 5.08)
          (name "POC_GPIO_6" (effects (font (size 1.27 1.27))))
          (number "F1" (effects (font (size 1.27 1.27))))
        )
        (pin bidirectional line (at 55.88 -88.9 180) (length 5.08)
          (name "POC_GPIO_4" (effects (font (size 1.27 1.27))))
          (number "F2" (effects (font (size 1.27 1.27))))
        )
        (pin passive line (at 55.88 -38.1 180) (length 5.08)
          (name "DPSRC_HPD" (effects (font (size 1.27 1.27))))
          (number "G1" (effects (font (size 1.27 1.27))))
        )
        (pin bidirectional line (at 55.88 -86.36 180) (length 5.08)
          (name "POC_GPIO_3" (effects (font (size 1.27 1.27))))
          (number "H4" (effects (font (size 1.27 1.27))))
        )
        (pin output line (at 55.88 -25.4 180) (length 5.08)
          (name "DPSRC_ML3_N" (effects (font (size 1.27 1.27))))
          (number "J1" (effects (font (size 1.27 1.27))))
        )
        (pin output line (at 55.88 -22.86 180) (length 5.08)
          (name "DPSRC_ML3_P" (effects (font (size 1.27 1.27))))
          (number "J2" (effects (font (size 1.27 1.27))))
        )
        (pin bidirectional line (at 55.88 -78.74 180) (length 5.08)
          (name "POC_GPIO_0" (effects (font (size 1.27 1.27))))
          (number "J4" (effects (font (size 1.27 1.27))))
        )
        (pin output line (at 55.88 -17.78 180) (length 5.08)
          (name "DPSRC_ML2_N" (effects (font (size 1.27 1.27))))
          (number "L1" (effects (font (size 1.27 1.27))))
        )
        (pin output line (at 55.88 -15.24 180) (length 5.08)
          (name "DPSRC_ML2_P" (effects (font (size 1.27 1.27))))
          (number "L2" (effects (font (size 1.27 1.27))))
        )
        (pin output line (at 55.88 -10.16 180) (length 5.08)
          (name "DPSRC_ML1_N" (effects (font (size 1.27 1.27))))
          (number "N1" (effects (font (size 1.27 1.27))))
        )
        (pin output line (at 55.88 -7.62 180) (length 5.08)
          (name "DPSRC_ML1_P" (effects (font (size 1.27 1.27))))
          (number "N2" (effects (font (size 1.27 1.27))))
        )
        (pin passive line (at 0 -99.06 0) (length 5.08)
          (name "DPSNK1_DDC_DATA" (effects (font (size 1.27 1.27))))
          (number "N4" (effects (font (size 1.27 1.27))))
        )
        (pin passive line (at 55.88 -43.18 180) (length 5.08)
          (name "DPSRC_RBIAS" (effects (font (size 1.27 1.27))))
          (number "N6" (effects (font (size 1.27 1.27))))
        )
        (pin output line (at 55.88 -2.54 180) (length 5.08)
          (name "DPSRC_ML0_N" (effects (font (size 1.27 1.27))))
          (number "R1" (effects (font (size 1.27 1.27))))
        )
        (pin output line (at 55.88 0 180) (length 5.08)
          (name "DPSRC_ML0_P" (effects (font (size 1.27 1.27))))
          (number "R2" (effects (font (size 1.27 1.27))))
        )
        (pin passive line (at 0 -45.72 0) (length 5.08)
          (name "DPSNK0_DDC_DATA" (effects (font (size 1.27 1.27))))
          (number "R4" (effects (font (size 1.27 1.27))))
        )
        (pin bidirectional line (at 55.88 -50.8 180) (length 5.08)
          (name "GPIO_0" (effects (font (size 1.27 1.27))))
          (number "U1" (effects (font (size 1.27 1.27))))
        )
        (pin bidirectional line (at 55.88 -53.34 180) (length 5.08)
          (name "GPIO_1" (effects (font (size 1.27 1.27))))
          (number "U2" (effects (font (size 1.27 1.27))))
        )
        (pin bidirectional line (at 55.88 -55.88 180) (length 5.08)
          (name "GPIO_2" (effects (font (size 1.27 1.27))))
          (number "V1" (effects (font (size 1.27 1.27))))
        )
        (pin bidirectional line (at 55.88 -58.42 180) (length 5.08)
          (name "GPIO_3" (effects (font (size 1.27 1.27))))
          (number "V2" (effects (font (size 1.27 1.27))))
        )
        (pin bidirectional line (at 55.88 -60.96 180) (length 5.08)
          (name "GPIO_4" (effects (font (size 1.27 1.27))))
          (number "W1" (effects (font (size 1.27 1.27))))
        )
        (pin bidirectional line (at 0 -33.02 0) (length 5.08)
          (name "DPSNK0_AUX_N" (effects (font (size 1.27 1.27))))
          (number "W11" (effects (font (size 1.27 1.27))))
        )
        (pin bidirectional line (at 0 -86.36 0) (length 5.08)
          (name "DPSNK1_AUX_N" (effects (font (size 1.27 1.27))))
          (number "W12" (effects (font (size 1.27 1.27))))
        )
        (pin bidirectional line (at 55.88 -30.48 180) (length 5.08)
          (name "DPSRC_AUX_P" (effects (font (size 1.27 1.27))))
          (number "W19" (effects (font (size 1.27 1.27))))
        )
        (pin bidirectional line (at 55.88 -63.5 180) (length 5.08)
          (name "GPIO_5" (effects (font (size 1.27 1.27))))
          (number "W2" (effects (font (size 1.27 1.27))))
        )
        (pin bidirectional line (at 55.88 -66.04 180) (length 5.08)
          (name "GPIO_6" (effects (font (size 1.27 1.27))))
          (number "Y1" (effects (font (size 1.27 1.27))))
        )
        (pin bidirectional line (at 0 -30.48 0) (length 5.08)
          (name "DPSNK0_AUXP" (effects (font (size 1.27 1.27))))
          (number "Y11" (effects (font (size 1.27 1.27))))
        )
        (pin bidirectional line (at 0 -83.82 0) (length 5.08)
          (name "DPSNK1_AUXP" (effects (font (size 1.27 1.27))))
          (number "Y12" (effects (font (size 1.27 1.27))))
        )
        (pin passive line (at 0 -104.14 0) (length 5.08)
          (name "DPSNK_RBIAS" (effects (font (size 1.27 1.27))))
          (number "Y18" (effects (font (size 1.27 1.27))))
        )
        (pin bidirectional line (at 55.88 -33.02 180) (length 5.08)
          (name "DPSRC_AUX_N" (effects (font (size 1.27 1.27))))
          (number "Y19" (effects (font (size 1.27 1.27))))
        )
        (pin bidirectional line (at 55.88 -68.58 180) (length 5.08)
          (name "GPIO_7" (effects (font (size 1.27 1.27))))
          (number "Y2" (effects (font (size 1.27 1.27))))
        )
        (pin passive line (at 0 -43.18 0) (length 5.08)
          (name "DPSNK0_DDC_CLK" (effects (font (size 1.27 1.27))))
          (number "Y5" (effects (font (size 1.27 1.27))))
        )
        (pin passive line (at 0 -91.44 0) (length 5.08)
          (name "DPSNK1_HPD" (effects (font (size 1.27 1.27))))
          (number "Y6" (effects (font (size 1.27 1.27))))
        )
        (pin passive line (at 0 -96.52 0) (length 5.08)
          (name "DPSNK1_DDC_CLK" (effects (font (size 1.27 1.27))))
          (number "Y8" (effects (font (size 1.27 1.27))))
        )
      )
      (symbol "JHL6340SLLSQ_4_0"
        (text "MISCELLANEOUS" (at 20.32 -13.97 0)
          (effects (font (size 1.27 1.27) (thickness 0.15)) (justify left bottom))
        )
      )
      (symbol "JHL6340SLLSQ_4_1"
        (rectangle (start 5.08 3.81) (end 50.8 -29.21)
          (stroke (width 0.254) (type default))
          (fill (type background))
        )
        (pin output line (at 55.88 -17.78 180) (length 5.08)
          (name "EE_DI" (effects (font (size 1.27 1.27))))
          (number "AB3" (effects (font (size 1.27 1.27))))
        )
        (pin output line (at 55.88 -25.4 180) (length 5.08)
          (name "EE_CLK" (effects (font (size 1.27 1.27))))
          (number "AB4" (effects (font (size 1.27 1.27))))
        )
        (pin input line (at 55.88 -2.54 180) (length 5.08)
          (name "TEST_PWR_GOOD" (effects (font (size 1.27 1.27))))
          (number "AB5" (effects (font (size 1.27 1.27))))
        )
        (pin output line (at 55.88 -22.86 180) (length 5.08)
          (name "EE_CS_N" (effects (font (size 1.27 1.27))))
          (number "AC3" (effects (font (size 1.27 1.27))))
        )
        (pin input line (at 55.88 -20.32 180) (length 5.08)
          (name "EE_D0" (effects (font (size 1.27 1.27))))
          (number "AC4" (effects (font (size 1.27 1.27))))
        )
        (pin input line (at 55.88 -10.16 180) (length 5.08)
          (name "XTAL_25_IN" (effects (font (size 1.27 1.27))))
          (number "D22" (effects (font (size 1.27 1.27))))
        )
        (pin input line (at 55.88 -12.7 180) (length 5.08)
          (name "XTAL_25_OUT" (effects (font (size 1.27 1.27))))
          (number "D23" (effects (font (size 1.27 1.27))))
        )
        (pin input line (at 55.88 0 180) (length 5.08)
          (name "TEST_EN" (effects (font (size 1.27 1.27))))
          (number "E1" (effects (font (size 1.27 1.27))))
        )
        (pin input line (at 55.88 -5.08 180) (length 5.08)
          (name "RESET_N" (effects (font (size 1.27 1.27))))
          (number "F4" (effects (font (size 1.27 1.27))))
        )
        (pin passive line (at 0 -12.7 0) (length 5.08)
          (name "RBIAS" (effects (font (size 1.27 1.27))))
          (number "H6" (effects (font (size 1.27 1.27))))
        )
        (pin passive line (at 0 -25.4 0) (length 5.08)
          (name "RSENSE" (effects (font (size 1.27 1.27))))
          (number "J6" (effects (font (size 1.27 1.27))))
        )
        (pin input line (at 0 -5.08 0) (length 5.08)
          (name "TCK" (effects (font (size 1.27 1.27))))
          (number "T4" (effects (font (size 1.27 1.27))))
        )
        (pin input line (at 0 -2.54 0) (length 5.08)
          (name "TMS" (effects (font (size 1.27 1.27))))
          (number "V4" (effects (font (size 1.27 1.27))))
        )
        (pin output line (at 0 -7.62 0) (length 5.08)
          (name "TDO" (effects (font (size 1.27 1.27))))
          (number "W4" (effects (font (size 1.27 1.27))))
        )
        (pin input line (at 0 0 0) (length 5.08)
          (name "TDI" (effects (font (size 1.27 1.27))))
          (number "Y4" (effects (font (size 1.27 1.27))))
        )
      )
      (symbol "JHL6340SLLSQ_5_0"
        (polyline
          (pts
            (xy 15.24 2.54)
            (xy 24.13 2.54)
            (xy 24.13 -58.42)
            (xy 13.97 -58.42)
          )
          (stroke (width 0) (type default))
          (fill (type none))
        )
        (polyline
          (pts
            (xy 40.64 2.54)
            (xy 31.75 2.54)
            (xy 31.75 -58.42)
            (xy 41.91 -58.42)
          )
          (stroke (width 0) (type default))
          (fill (type none))
        )
        (text "TBT PORT A" (at 26.67 -31.75 900)
          (effects (font (size 1.27 1.27) (thickness 0.15)) (justify left bottom))
        )
        (text "TBT PORT B" (at 31.115 -31.75 900)
          (effects (font (size 1.27 1.27) (thickness 0.15)) (justify left bottom))
        )
      )
      (symbol "JHL6340SLLSQ_5_1"
        (rectangle (start 5.08 3.81) (end 50.8 -59.69)
          (stroke (width 0.254) (type default))
          (fill (type background))
        )
        (pin output line (at 55.88 -15.24 180) (length 5.08)
          (name "PB_TX0_P" (effects (font (size 1.27 1.27))))
          (number "A11" (effects (font (size 1.27 1.27))))
        )
        (pin input line (at 55.88 0 180) (length 5.08)
          (name "PB_RX0_P" (effects (font (size 1.27 1.27))))
          (number "A13" (effects (font (size 1.27 1.27))))
        )
        (pin input line (at 0 -7.62 0) (length 5.08)
          (name "PA_RX1_P" (effects (font (size 1.27 1.27))))
          (number "A15" (effects (font (size 1.27 1.27))))
        )
        (pin output line (at 0 -22.86 0) (length 5.08)
          (name "PA_TX1_P" (effects (font (size 1.27 1.27))))
          (number "A17" (effects (font (size 1.27 1.27))))
        )
        (pin output line (at 0 -15.24 0) (length 5.08)
          (name "PA_TX0_P" (effects (font (size 1.27 1.27))))
          (number "A19" (effects (font (size 1.27 1.27))))
        )
        (pin input line (at 0 -2.54 0) (length 5.08)
          (name "PA_RX0_N" (effects (font (size 1.27 1.27))))
          (number "A21" (effects (font (size 1.27 1.27))))
        )
        (pin input line (at 0 -48.26 0) (length 5.08)
          (name "PA_LSRX" (effects (font (size 1.27 1.27))))
          (number "A4" (effects (font (size 1.27 1.27))))
        )
        (pin output line (at 0 -45.72 0) (length 5.08)
          (name "PA_LSTX" (effects (font (size 1.27 1.27))))
          (number "A5" (effects (font (size 1.27 1.27))))
        )
        (pin input line (at 55.88 -10.16 180) (length 5.08)
          (name "PB_RX1_N" (effects (font (size 1.27 1.27))))
          (number "A7" (effects (font (size 1.27 1.27))))
        )
        (pin output line (at 55.88 -22.86 180) (length 5.08)
          (name "PB_TX1_P" (effects (font (size 1.27 1.27))))
          (number "A9" (effects (font (size 1.27 1.27))))
        )
        (pin output line (at 55.88 -17.78 180) (length 5.08)
          (name "PB_TX0_N" (effects (font (size 1.27 1.27))))
          (number "B11" (effects (font (size 1.27 1.27))))
        )
        (pin input line (at 55.88 -2.54 180) (length 5.08)
          (name "PB_RX0_N" (effects (font (size 1.27 1.27))))
          (number "B13" (effects (font (size 1.27 1.27))))
        )
        (pin input line (at 0 -10.16 0) (length 5.08)
          (name "PA_RX1_N" (effects (font (size 1.27 1.27))))
          (number "B15" (effects (font (size 1.27 1.27))))
        )
        (pin output line (at 0 -25.4 0) (length 5.08)
          (name "PA_TX1_N" (effects (font (size 1.27 1.27))))
          (number "B17" (effects (font (size 1.27 1.27))))
        )
        (pin output line (at 0 -17.78 0) (length 5.08)
          (name "PA_TX0_N" (effects (font (size 1.27 1.27))))
          (number "B19" (effects (font (size 1.27 1.27))))
        )
        (pin input line (at 0 0 0) (length 5.08)
          (name "PA_RX0_P" (effects (font (size 1.27 1.27))))
          (number "B21" (effects (font (size 1.27 1.27))))
        )
        (pin output line (at 55.88 -45.72 180) (length 5.08)
          (name "PB_LSTX" (effects (font (size 1.27 1.27))))
          (number "B4" (effects (font (size 1.27 1.27))))
        )
        (pin input line (at 55.88 -48.26 180) (length 5.08)
          (name "PB_LSRX" (effects (font (size 1.27 1.27))))
          (number "B5" (effects (font (size 1.27 1.27))))
        )
        (pin input line (at 55.88 -7.62 180) (length 5.08)
          (name "PB_RX1_P" (effects (font (size 1.27 1.27))))
          (number "B7" (effects (font (size 1.27 1.27))))
        )
        (pin output line (at 55.88 -25.4 180) (length 5.08)
          (name "PB_TX1_N" (effects (font (size 1.27 1.27))))
          (number "B9" (effects (font (size 1.27 1.27))))
        )
        (pin bidirectional line (at 55.88 -40.64 180) (length 5.08)
          (name "PB_USB2_D_N" (effects (font (size 1.27 1.27))))
          (number "D19" (effects (font (size 1.27 1.27))))
        )
        (pin bidirectional line (at 0 -40.64 0) (length 5.08)
          (name "PA_USB2_D_N" (effects (font (size 1.27 1.27))))
          (number "D20" (effects (font (size 1.27 1.27))))
        )
        (pin bidirectional line (at 55.88 -38.1 180) (length 5.08)
          (name "PB_USB2_D_P" (effects (font (size 1.27 1.27))))
          (number "E19" (effects (font (size 1.27 1.27))))
        )
        (pin bidirectional line (at 0 -38.1 0) (length 5.08)
          (name "PA_USB2_D_P" (effects (font (size 1.27 1.27))))
          (number "E20" (effects (font (size 1.27 1.27))))
        )
        (pin passive line (at 55.88 -55.88 180) (length 5.08)
          (name "PB_USB2_RBIAS" (effects (font (size 1.27 1.27))))
          (number "F19" (effects (font (size 1.27 1.27))))
        )
        (pin input line (at 55.88 -50.8 180) (length 5.08)
          (name "PB_DPSRC_HPD" (effects (font (size 1.27 1.27))))
          (number "G2" (effects (font (size 1.27 1.27))))
        )
        (pin passive line (at 0 -55.88 0) (length 5.08)
          (name "PA_USB2_RBIAS" (effects (font (size 1.27 1.27))))
          (number "H19" (effects (font (size 1.27 1.27))))
        )
        (pin input line (at 0 -50.8 0) (length 5.08)
          (name "PA_DPSRC_HPD" (effects (font (size 1.27 1.27))))
          (number "M4" (effects (font (size 1.27 1.27))))
        )
        (pin bidirectional line (at 0 -33.02 0) (length 5.08)
          (name "PA_DPSRC_AUX_N" (effects (font (size 1.27 1.27))))
          (number "W15" (effects (font (size 1.27 1.27))))
        )
        (pin bidirectional line (at 55.88 -33.02 180) (length 5.08)
          (name "PB_DPSRC_AUX_N" (effects (font (size 1.27 1.27))))
          (number "W16" (effects (font (size 1.27 1.27))))
        )
        (pin bidirectional line (at 0 -30.48 0) (length 5.08)
          (name "PA_DPSRC_AUX_P" (effects (font (size 1.27 1.27))))
          (number "Y15" (effects (font (size 1.27 1.27))))
        )
        (pin bidirectional line (at 55.88 -30.48 180) (length 5.08)
          (name "PB_DPSRC_AUX_P" (effects (font (size 1.27 1.27))))
          (number "Y16" (effects (font (size 1.27 1.27))))
        )
      )
      (symbol "JHL6340SLLSQ_6_0"
        (text "DEBUG" (at 24.13 -15.24 0)
          (effects (font (size 1.27 1.27) (thickness 0.15)) (justify left bottom))
        )
      )
      (symbol "JHL6340SLLSQ_6_1"
        (rectangle (start 5.08 3.81) (end 50.8 -31.75)
          (stroke (width 0.254) (type default))
          (fill (type background))
        )
        (pin passive line (at 55.88 -5.08 180) (length 5.08)
          (name "ATEST_P" (effects (font (size 1.27 1.27))))
          (number "A23" (effects (font (size 1.27 1.27))))
        )
        (pin passive line (at 55.88 -25.4 180) (length 5.08)
          (name "MONDC_DPSRC" (effects (font (size 1.27 1.27))))
          (number "AB2" (effects (font (size 1.27 1.27))))
        )
        (pin passive line (at 0 0 0) (length 5.08)
          (name "THERMDA2" (effects (font (size 1.27 1.27))))
          (number "AB23" (effects (font (size 1.27 1.27))))
        )
        (pin passive line (at 0 -12.7 0) (length 5.08)
          (name "TEST_EDM" (effects (font (size 1.27 1.27))))
          (number "AC1" (effects (font (size 1.27 1.27))))
        )
        (pin passive line (at 0 -2.54 0) (length 5.08)
          (name "THERMDA1" (effects (font (size 1.27 1.27))))
          (number "AC23" (effects (font (size 1.27 1.27))))
        )
        (pin passive line (at 55.88 -7.62 180) (length 5.08)
          (name "ATEST_N" (effects (font (size 1.27 1.27))))
          (number "B23" (effects (font (size 1.27 1.27))))
        )
        (pin passive line (at 0 -27.94 0) (length 5.08)
          (name "MONDC_CIO_1" (effects (font (size 1.27 1.27))))
          (number "C22" (effects (font (size 1.27 1.27))))
        )
        (pin passive line (at 0 -25.4 0) (length 5.08)
          (name "MONDC_CIO_0" (effects (font (size 1.27 1.27))))
          (number "C23" (effects (font (size 1.27 1.27))))
        )
        (pin passive line (at 55.88 0 180) (length 5.08)
          (name "MONDC_SVR" (effects (font (size 1.27 1.27))))
          (number "D6" (effects (font (size 1.27 1.27))))
        )
        (pin passive line (at 55.88 -12.7 180) (length 5.08)
          (name "USB2_ATEST" (effects (font (size 1.27 1.27))))
          (number "E18" (effects (font (size 1.27 1.27))))
        )
        (pin passive line (at 0 -17.78 0) (length 5.08)
          (name "FUSE_VQPS_64" (effects (font (size 1.27 1.27))))
          (number "L15" (effects (font (size 1.27 1.27))))
        )
        (pin passive line (at 0 -20.32 0) (length 5.08)
          (name "FUSE_VQPS_128" (effects (font (size 1.27 1.27))))
          (number "N15" (effects (font (size 1.27 1.27))))
        )
        (pin passive line (at 0 -7.62 0) (length 5.08)
          (name "PCIE_ATEST" (effects (font (size 1.27 1.27))))
          (number "V18" (effects (font (size 1.27 1.27))))
        )
        (pin passive line (at 55.88 -17.78 180) (length 5.08)
          (name "MONDC_DPSNK_0" (effects (font (size 1.27 1.27))))
          (number "W13" (effects (font (size 1.27 1.27))))
        )
        (pin passive line (at 55.88 -20.32 180) (length 5.08)
          (name "MONDC_DPSNK_1" (effects (font (size 1.27 1.27))))
          (number "W18" (effects (font (size 1.27 1.27))))
        )
      )
    )
	(symbol "antmicroInterfaceControllers:TPS65983BAZBHR" (in_bom yes) (on_board yes)
      (property "Reference" "U" (at 73.66 2.54 0)
        (effects (font (size 1.27 1.27) (thickness 0.15)) (justify left bottom))
      )
      (property "Value" "TPS65983BAZBHR" (at 73.66 0 0)
        (effects (font (size 1.27 1.27) (thickness 0.15)) (justify left bottom) hide)
      )
      (property "Footprint" "antmicro-footprints:IC_TPS65983BAZBHR" (at 73.66 -2.54 0)
        (effects (font (size 1.27 1.27) (thickness 0.15)) (justify left bottom) hide)
      )
      (property "Datasheet" "https://www.ti.com/lit/ds/symlink/tps65983b.pdf?ts=1678712702533&ref_url=https%253A%252F%252Fwww.ti.com%252Fproduct%252FTPS65983B" (at 73.66 -5.08 0)
        (effects (font (size 1.27 1.27) (thickness 0.15)) (justify left bottom) hide)
      )
      (property "MPN" "TPS65983BAZBHR" (at 73.66 -7.62 0)
        (effects (font (size 1.27 1.27) (thickness 0.15)) (justify left bottom))
      )
      (property "Manufacturer" "Texas Instruments" (at 73.66 -10.16 0)
        (effects (font (size 1.27 1.27) (thickness 0.15)) (justify left bottom) hide)
      )
      (property "Author" "Antmicro" (at 73.66 -12.7 0)
        (effects (font (size 1.27 1.27) (thickness 0.15)) (justify left bottom) hide)
      )
      (property "License" "Apache-2.0" (at 73.66 -15.24 0)
        (effects (font (size 1.27 1.27) (thickness 0.15)) (justify left bottom) hide)
      )
      (property "ki_keywords" "IC" (at 0 0 0)
        (effects (font (size 1.27 1.27)) hide)
      )
      (property "ki_description" "USB Interface IC Universal USB Type-C and Power Delivery (PD) 3.0 controller 96-NFBGA -10°C to 85" (at 0 0 0)
        (effects (font (size 1.27 1.27)) hide)
      )
      (symbol "TPS65983BAZBHR_0_1"
        (rectangle (start 3.81 5.08) (end 54.61 -129.54)
          (stroke (width 0) (type default))
          (fill (type background))
        )
      )
      (symbol "TPS65983BAZBHR_1_1"
        (pin power_in line (at 0 -127 0) (length 3.81)
          (name "GND" (effects (font (size 1.27 1.27))))
          (number "A1" (effects (font (size 1.27 1.27))))
        )
        (pin input line (at 0 0 0) (length 3.81)
          (name "SENSEN" (effects (font (size 1.27 1.27))))
          (number "A10" (effects (font (size 1.27 1.27))))
        )
        (pin power_in line (at 0 -10.16 0) (length 3.81)
          (name "PP_5V0" (effects (font (size 1.27 1.27))))
          (number "A11" (effects (font (size 1.27 1.27))))
        )
        (pin power_out line (at 58.42 -22.86 180) (length 3.81)
          (name "LDO_1V8D" (effects (font (size 1.27 1.27))))
          (number "A2" (effects (font (size 1.27 1.27))))
        )
        (pin output line (at 0 -76.2 0) (length 3.81)
          (name "SPI_CLK" (effects (font (size 1.27 1.27))))
          (number "A3" (effects (font (size 1.27 1.27))))
        )
        (pin input line (at 0 -81.28 0) (length 3.81)
          (name "SPI_POCI" (effects (font (size 1.27 1.27))))
          (number "A4" (effects (font (size 1.27 1.27))))
        )
        (pin bidirectional line (at 0 -40.64 0) (length 3.81)
          (name "I2C_SDA2" (effects (font (size 1.27 1.27))))
          (number "A5" (effects (font (size 1.27 1.27))))
        )
        (pin power_in line (at 0 -5.08 0) (length 3.81)
          (name "PP_HV" (effects (font (size 1.27 1.27))))
          (number "A6" (effects (font (size 1.27 1.27))))
        )
        (pin power_in line (at 0 -5.08 0) (length 3.81) hide
          (name "PP_HV" (effects (font (size 1.27 1.27))))
          (number "A7" (effects (font (size 1.27 1.27))))
        )
        (pin power_in line (at 0 -5.08 0) (length 3.81) hide
          (name "PP_HV" (effects (font (size 1.27 1.27))))
          (number "A8" (effects (font (size 1.27 1.27))))
        )
        (pin output line (at 58.42 0 180) (length 3.81)
          (name "HV_GATE2" (effects (font (size 1.27 1.27))))
          (number "A9" (effects (font (size 1.27 1.27))))
        )
        (pin power_in line (at 0 -20.32 0) (length 3.81)
          (name "VDDIO" (effects (font (size 1.27 1.27))))
          (number "B1" (effects (font (size 1.27 1.27))))
        )
        (pin input line (at 0 2.54 0) (length 3.81)
          (name "SENSEP" (effects (font (size 1.27 1.27))))
          (number "B10" (effects (font (size 1.27 1.27))))
        )
        (pin power_in line (at 0 -10.16 0) (length 3.81) hide
          (name "PP_5V0" (effects (font (size 1.27 1.27))))
          (number "B11" (effects (font (size 1.27 1.27))))
        )
        (pin bidirectional line (at 0 -50.8 0) (length 3.81)
          (name "GPIO0(HD3_AMSEL)" (effects (font (size 1.27 1.27))))
          (number "B2" (effects (font (size 1.27 1.27))))
        )
        (pin output line (at 0 -83.82 0) (length 3.81)
          (name "SPI_CSZ" (effects (font (size 1.27 1.27))))
          (number "B3" (effects (font (size 1.27 1.27))))
        )
        (pin output line (at 0 -78.74 0) (length 3.81)
          (name "SPI_PICO" (effects (font (size 1.27 1.27))))
          (number "B4" (effects (font (size 1.27 1.27))))
        )
        (pin bidirectional line (at 0 -43.18 0) (length 3.81)
          (name "I2C_SCL2" (effects (font (size 1.27 1.27))))
          (number "B5" (effects (font (size 1.27 1.27))))
        )
        (pin output line (at 0 -45.72 0) (length 3.81)
          (name "I2C_IRQ2Z" (effects (font (size 1.27 1.27))))
          (number "B6" (effects (font (size 1.27 1.27))))
        )
        (pin power_in line (at 0 -5.08 0) (length 3.81) hide
          (name "PP_HV" (effects (font (size 1.27 1.27))))
          (number "B7" (effects (font (size 1.27 1.27))))
        )
        (pin power_in line (at 0 -127 0) (length 3.81) hide
          (name "GND" (effects (font (size 1.27 1.27))))
          (number "B8" (effects (font (size 1.27 1.27))))
        )
        (pin output line (at 58.42 2.54 180) (length 3.81)
          (name "HV_GATE1" (effects (font (size 1.27 1.27))))
          (number "B9" (effects (font (size 1.27 1.27))))
        )
        (pin output line (at 0 -35.56 0) (length 3.81)
          (name "I2C_IRQ1Z" (effects (font (size 1.27 1.27))))
          (number "C1" (effects (font (size 1.27 1.27))))
        )
        (pin bidirectional line (at 0 -60.96 0) (length 3.81)
          (name "GPIO4(HPD_TXRX)" (effects (font (size 1.27 1.27))))
          (number "C10" (effects (font (size 1.27 1.27))))
        )
        (pin power_in line (at 0 -10.16 0) (length 3.81) hide
          (name "PP_5V0" (effects (font (size 1.27 1.27))))
          (number "C11" (effects (font (size 1.27 1.27))))
        )
        (pin bidirectional line (at 0 -53.34 0) (length 3.81)
          (name "GPIO1(CONFIG0)" (effects (font (size 1.27 1.27))))
          (number "C2" (effects (font (size 1.27 1.27))))
        )
        (pin bidirectional line (at 0 -30.48 0) (length 3.81)
          (name "I2C_SDA1" (effects (font (size 1.27 1.27))))
          (number "D1" (effects (font (size 1.27 1.27))))
        )
        (pin bidirectional line (at 0 -55.88 0) (length 3.81)
          (name "GPIO2" (effects (font (size 1.27 1.27))))
          (number "D10" (effects (font (size 1.27 1.27))))
        )
        (pin power_in line (at 0 -10.16 0) (length 3.81) hide
          (name "PP_5V0" (effects (font (size 1.27 1.27))))
          (number "D11" (effects (font (size 1.27 1.27))))
        )
        (pin bidirectional line (at 0 -33.02 0) (length 3.81)
          (name "I2C_SCL1" (effects (font (size 1.27 1.27))))
          (number "D2" (effects (font (size 1.27 1.27))))
        )
        (pin bidirectional line (at 58.42 -83.82 180) (length 3.81)
          (name "DEBUG_CTL2(GPIO17,_I2CADDR_B5)" (effects (font (size 1.27 1.27))))
          (number "D5" (effects (font (size 1.27 1.27))))
        )
        (pin input line (at 58.42 -106.68 180) (length 3.81)
          (name "HRESET" (effects (font (size 1.27 1.27))))
          (number "D6" (effects (font (size 1.27 1.27))))
        )
        (pin bidirectional line (at 0 -68.58 0) (length 3.81)
          (name "GPIO7" (effects (font (size 1.27 1.27))))
          (number "D7" (effects (font (size 1.27 1.27))))
        )
        (pin power_in line (at 0 -127 0) (length 3.81) hide
          (name "GND" (effects (font (size 1.27 1.27))))
          (number "D8" (effects (font (size 1.27 1.27))))
        )
        (pin power_out line (at 58.42 -27.94 180) (length 3.81)
          (name "LDO_BMC" (effects (font (size 1.27 1.27))))
          (number "E1" (effects (font (size 1.27 1.27))))
        )
        (pin bidirectional line (at 0 -63.5 0) (length 3.81)
          (name "GPIO5(HPD_RX)" (effects (font (size 1.27 1.27))))
          (number "E10" (effects (font (size 1.27 1.27))))
        )
        (pin bidirectional line (at 58.42 -101.6 180) (length 3.81)
          (name "MRESET(GPIO11)" (effects (font (size 1.27 1.27))))
          (number "E11" (effects (font (size 1.27 1.27))))
        )
        (pin output line (at 0 -99.06 0) (length 3.81)
          (name "UART_TX" (effects (font (size 1.27 1.27))))
          (number "E2" (effects (font (size 1.27 1.27))))
        )
        (pin bidirectional line (at 58.42 -86.36 180) (length 3.81)
          (name "DEBUG_CTL1(GPIO16,_I2CADDR_B4)" (effects (font (size 1.27 1.27))))
          (number "E4" (effects (font (size 1.27 1.27))))
        )
        (pin power_in line (at 0 -127 0) (length 3.81) hide
          (name "GND" (effects (font (size 1.27 1.27))))
          (number "E5" (effects (font (size 1.27 1.27))))
        )
        (pin power_in line (at 0 -127 0) (length 3.81) hide
          (name "GND" (effects (font (size 1.27 1.27))))
          (number "E6" (effects (font (size 1.27 1.27))))
        )
        (pin power_in line (at 0 -127 0) (length 3.81) hide
          (name "GND" (effects (font (size 1.27 1.27))))
          (number "E7" (effects (font (size 1.27 1.27))))
        )
        (pin power_in line (at 0 -127 0) (length 3.81) hide
          (name "GND" (effects (font (size 1.27 1.27))))
          (number "E8" (effects (font (size 1.27 1.27))))
        )
        (pin bidirectional line (at 58.42 -91.44 180) (length 3.81)
          (name "I2C_ADDR" (effects (font (size 1.27 1.27))))
          (number "F1" (effects (font (size 1.27 1.27))))
        )
        (pin bidirectional line (at 58.42 -111.76 180) (length 3.81)
          (name "BUSPOWERZ(GPIO10)" (effects (font (size 1.27 1.27))))
          (number "F10" (effects (font (size 1.27 1.27))))
        )
        (pin bidirectional line (at 58.42 -96.52 180) (length 3.81)
          (name "RESETZ(GPIO9)" (effects (font (size 1.27 1.27))))
          (number "F11" (effects (font (size 1.27 1.27))))
        )
        (pin input line (at 0 -96.52 0) (length 3.81)
          (name "UART_RX" (effects (font (size 1.27 1.27))))
          (number "F2" (effects (font (size 1.27 1.27))))
        )
        (pin bidirectional line (at 0 -88.9 0) (length 3.81)
          (name "SWD_DATA" (effects (font (size 1.27 1.27))))
          (number "F4" (effects (font (size 1.27 1.27))))
        )
        (pin power_in line (at 0 -127 0) (length 3.81) hide
          (name "GND" (effects (font (size 1.27 1.27))))
          (number "F5" (effects (font (size 1.27 1.27))))
        )
        (pin power_in line (at 0 -127 0) (length 3.81) hide
          (name "GND" (effects (font (size 1.27 1.27))))
          (number "F6" (effects (font (size 1.27 1.27))))
        )
        (pin power_in line (at 0 -127 0) (length 3.81) hide
          (name "GND" (effects (font (size 1.27 1.27))))
          (number "F7" (effects (font (size 1.27 1.27))))
        )
        (pin power_in line (at 0 -127 0) (length 3.81) hide
          (name "GND" (effects (font (size 1.27 1.27))))
          (number "F8" (effects (font (size 1.27 1.27))))
        )
        (pin power_out line (at 58.42 -12.7 180) (length 3.81)
          (name "LDO_3V3" (effects (font (size 1.27 1.27))))
          (number "G1" (effects (font (size 1.27 1.27))))
        )
        (pin bidirectional line (at 0 -66.04 0) (length 3.81)
          (name "GPIO6" (effects (font (size 1.27 1.27))))
          (number "G10" (effects (font (size 1.27 1.27))))
        )
        (pin bidirectional line (at 0 -58.42 0) (length 3.81)
          (name "GPIO3(HD3_EN)" (effects (font (size 1.27 1.27))))
          (number "G11" (effects (font (size 1.27 1.27))))
        )
        (pin bidirectional line (at 58.42 -116.84 180) (length 3.81)
          (name "R_OSC" (effects (font (size 1.27 1.27))))
          (number "G2" (effects (font (size 1.27 1.27))))
        )
        (pin input line (at 0 -91.44 0) (length 3.81)
          (name "SWD_CLK" (effects (font (size 1.27 1.27))))
          (number "G4" (effects (font (size 1.27 1.27))))
        )
        (pin power_in line (at 0 -127 0) (length 3.81) hide
          (name "GND" (effects (font (size 1.27 1.27))))
          (number "G5" (effects (font (size 1.27 1.27))))
        )
        (pin power_in line (at 0 -127 0) (length 3.81) hide
          (name "GND" (effects (font (size 1.27 1.27))))
          (number "G6" (effects (font (size 1.27 1.27))))
        )
        (pin power_in line (at 0 -127 0) (length 3.81) hide
          (name "GND" (effects (font (size 1.27 1.27))))
          (number "G7" (effects (font (size 1.27 1.27))))
        )
        (pin power_in line (at 0 -127 0) (length 3.81) hide
          (name "GND" (effects (font (size 1.27 1.27))))
          (number "G8" (effects (font (size 1.27 1.27))))
        )
        (pin power_in line (at 0 -25.4 0) (length 3.81)
          (name "VIN_3V3" (effects (font (size 1.27 1.27))))
          (number "H1" (effects (font (size 1.27 1.27))))
        )
        (pin power_in line (at 0 -15.24 0) (length 3.81)
          (name "PP_CABLE" (effects (font (size 1.27 1.27))))
          (number "H10" (effects (font (size 1.27 1.27))))
        )
        (pin power_in line (at 58.42 -5.08 180) (length 3.81)
          (name "VBUS" (effects (font (size 1.27 1.27))))
          (number "H11" (effects (font (size 1.27 1.27))))
        )
        (pin power_out line (at 58.42 -7.62 180) (length 3.81)
          (name "VOUT_3V3" (effects (font (size 1.27 1.27))))
          (number "H2" (effects (font (size 1.27 1.27))))
        )
        (pin power_in line (at 0 -127 0) (length 3.81) hide
          (name "GND" (effects (font (size 1.27 1.27))))
          (number "H4" (effects (font (size 1.27 1.27))))
        )
        (pin power_in line (at 0 -127 0) (length 3.81) hide
          (name "GND" (effects (font (size 1.27 1.27))))
          (number "H5" (effects (font (size 1.27 1.27))))
        )
        (pin bidirectional line (at 0 -71.12 0) (length 3.81)
          (name "GPIO8" (effects (font (size 1.27 1.27))))
          (number "H6" (effects (font (size 1.27 1.27))))
        )
        (pin output line (at 58.42 -121.92 180) (length 3.81)
          (name "SS" (effects (font (size 1.27 1.27))))
          (number "H7" (effects (font (size 1.27 1.27))))
        )
        (pin power_in line (at 0 -127 0) (length 3.81) hide
          (name "GND" (effects (font (size 1.27 1.27))))
          (number "H8" (effects (font (size 1.27 1.27))))
        )
        (pin bidirectional line (at 0 -111.76 0) (length 3.81)
          (name "AUX_P" (effects (font (size 1.27 1.27))))
          (number "J1" (effects (font (size 1.27 1.27))))
        )
        (pin power_in line (at 58.42 -5.08 180) (length 3.81) hide
          (name "VBUS" (effects (font (size 1.27 1.27))))
          (number "J10" (effects (font (size 1.27 1.27))))
        )
        (pin power_in line (at 58.42 -5.08 180) (length 3.81) hide
          (name "VBUS" (effects (font (size 1.27 1.27))))
          (number "J11" (effects (font (size 1.27 1.27))))
        )
        (pin bidirectional line (at 0 -114.3 0) (length 3.81)
          (name "AUX_N" (effects (font (size 1.27 1.27))))
          (number "J2" (effects (font (size 1.27 1.27))))
        )
        (pin power_out line (at 58.42 -17.78 180) (length 3.81)
          (name "LDO_1V8A" (effects (font (size 1.27 1.27))))
          (number "K1" (effects (font (size 1.27 1.27))))
        )
        (pin bidirectional line (at 58.42 -43.18 180) (length 3.81)
          (name "RPD_G2" (effects (font (size 1.27 1.27))))
          (number "K10" (effects (font (size 1.27 1.27))))
        )
        (pin power_in line (at 58.42 -5.08 180) (length 3.81) hide
          (name "VBUS" (effects (font (size 1.27 1.27))))
          (number "K11" (effects (font (size 1.27 1.27))))
        )
        (pin bidirectional line (at 58.42 -76.2 180) (length 3.81)
          (name "DEBUG2(GPIO14,HD3POL)" (effects (font (size 1.27 1.27))))
          (number "K2" (effects (font (size 1.27 1.27))))
        )
        (pin bidirectional line (at 58.42 -71.12 180) (length 3.81)
          (name "DEBUG4(GPIO12,CONFIG2)" (effects (font (size 1.27 1.27))))
          (number "K3" (effects (font (size 1.27 1.27))))
        )
        (pin output line (at 0 -106.68 0) (length 3.81)
          (name "LSX_P2R" (effects (font (size 1.27 1.27))))
          (number "K4" (effects (font (size 1.27 1.27))))
        )
        (pin bidirectional line (at 0 -121.92 0) (length 3.81)
          (name "USB_RP_N" (effects (font (size 1.27 1.27))))
          (number "K5" (effects (font (size 1.27 1.27))))
        )
        (pin bidirectional line (at 58.42 -48.26 180) (length 3.81)
          (name "C_USB_TP" (effects (font (size 1.27 1.27))))
          (number "K6" (effects (font (size 1.27 1.27))))
        )
        (pin bidirectional line (at 58.42 -55.88 180) (length 3.81)
          (name "C_USB_BP" (effects (font (size 1.27 1.27))))
          (number "K7" (effects (font (size 1.27 1.27))))
        )
        (pin bidirectional line (at 58.42 -63.5 180) (length 3.81)
          (name "C_SBU1" (effects (font (size 1.27 1.27))))
          (number "K8" (effects (font (size 1.27 1.27))))
        )
        (pin bidirectional line (at 58.42 -40.64 180) (length 3.81)
          (name "RPD_G1" (effects (font (size 1.27 1.27))))
          (number "K9" (effects (font (size 1.27 1.27))))
        )
        (pin power_in line (at 0 -127 0) (length 3.81) hide
          (name "GND" (effects (font (size 1.27 1.27))))
          (number "L1" (effects (font (size 1.27 1.27))))
        )
        (pin bidirectional line (at 58.42 -35.56 180) (length 3.81)
          (name "C_CC2" (effects (font (size 1.27 1.27))))
          (number "L10" (effects (font (size 1.27 1.27))))
        )
        (pin no_connect line (at 3.81 -123.19 0) (length 3.81) hide
          (name "NC" (effects (font (size 1.27 1.27))))
          (number "L11" (effects (font (size 1.27 1.27))))
        )
        (pin bidirectional line (at 58.42 -78.74 180) (length 3.81)
          (name "DEBUG1(GPIO15)" (effects (font (size 1.27 1.27))))
          (number "L2" (effects (font (size 1.27 1.27))))
        )
        (pin bidirectional line (at 58.42 -73.66 180) (length 3.81)
          (name "DEBUG3(GPIO13,CONFIG1)" (effects (font (size 1.27 1.27))))
          (number "L3" (effects (font (size 1.27 1.27))))
        )
        (pin input line (at 0 -104.14 0) (length 3.81)
          (name "LSX_R2P" (effects (font (size 1.27 1.27))))
          (number "L4" (effects (font (size 1.27 1.27))))
        )
        (pin bidirectional line (at 0 -119.38 0) (length 3.81)
          (name "USB_RP_P" (effects (font (size 1.27 1.27))))
          (number "L5" (effects (font (size 1.27 1.27))))
        )
        (pin bidirectional line (at 58.42 -50.8 180) (length 3.81)
          (name "C_USB_TN" (effects (font (size 1.27 1.27))))
          (number "L6" (effects (font (size 1.27 1.27))))
        )
        (pin bidirectional line (at 58.42 -58.42 180) (length 3.81)
          (name "C_USB_BN" (effects (font (size 1.27 1.27))))
          (number "L7" (effects (font (size 1.27 1.27))))
        )
        (pin bidirectional line (at 58.42 -66.04 180) (length 3.81)
          (name "C_SBU2" (effects (font (size 1.27 1.27))))
          (number "L8" (effects (font (size 1.27 1.27))))
        )
        (pin bidirectional line (at 58.42 -33.02 180) (length 3.81)
          (name "C_CC1" (effects (font (size 1.27 1.27))))
          (number "L9" (effects (font (size 1.27 1.27))))
        )
      )
    )
	(symbol "antmicroLEDIndicationDiscrete:LED_G_0603_KP-1608CGCK" (pin_numbers hide) (pin_names hide) (in_bom yes) (on_board yes)
      (property "Reference" "D" (at 22.86 -2.54 0)
        (effects (font (size 1.27 1.27) (thickness 0.15)) (justify left bottom))
      )
      (property "Value" "LED_G_0603_KP-1608CGCK" (at 22.86 -7.62 0)
        (effects (font (size 1.27 1.27) (thickness 0.15)) (justify left bottom) hide)
      )
      (property "Footprint" "antmicro-footprints:LED_0603_1608Metric_G" (at 22.86 -10.16 0)
        (effects (font (size 1.27 1.27) (thickness 0.15)) (justify left bottom) hide)
      )
      (property "Datasheet" "http://www.kingbright.com/attachments/file/psearch//000/00/00/KP-1608CGCK(Ver.23B).pdf" (at 22.86 -12.7 0)
        (effects (font (size 1.27 1.27) (thickness 0.15)) (justify left bottom) hide)
      )
      (property "MPN" "KP-1608CGCK" (at 22.86 -15.24 0)
        (effects (font (size 1.27 1.27) (thickness 0.15)) (justify left bottom) hide)
      )
      (property "Manufacturer" "Kingbright" (at 22.86 -17.78 0)
        (effects (font (size 1.27 1.27) (thickness 0.15)) (justify left bottom) hide)
      )
      (property "Color" "Green" (at 22.86 -5.08 0)
        (effects (font (size 1.27 1.27)) (justify left bottom))
      )
      (property "Author" "Antmicro" (at 22.86 -20.32 0)
        (effects (font (size 1.27 1.27) (thickness 0.15)) (justify left bottom) hide)
      )
      (property "License" "Apache-2.0" (at 22.86 -22.86 0)
        (effects (font (size 1.27 1.27) (thickness 0.15)) (justify left bottom) hide)
      )
      (property "ki_keywords" "SMT, DIODE, SEMICONDUCTOR, LED" (at 0 0 0)
        (effects (font (size 1.27 1.27)) hide)
      )
      (property "ki_description" "LED, Green, SMD, 0603, 20 mA, 2.1 V, 570 nm" (at 0 0 0)
        (effects (font (size 1.27 1.27)) hide)
      )
      (symbol "LED_G_0603_KP-1608CGCK_0_1"
        (polyline
          (pts
            (xy 1.905 0)
            (xy 0.635 0)
          )
          (stroke (width 0) (type default))
          (fill (type none))
        )
        (polyline
          (pts
            (xy 4.445 0)
            (xy 3.175 0)
          )
          (stroke (width 0) (type default))
          (fill (type none))
        )
      )
      (symbol "LED_G_0603_KP-1608CGCK_1_1"
        (polyline
          (pts
            (xy 1.778 1.016)
            (xy 1.778 -1.016)
          )
          (stroke (width 0.254) (type default))
          (fill (type none))
        )
        (polyline
          (pts
            (xy 3.302 1.016)
            (xy 3.302 -1.016)
            (xy 1.778 0)
            (xy 3.302 1.016)
          )
          (stroke (width 0.254) (type default))
          (fill (type outline))
        )
        (polyline
          (pts
            (xy 1.143 2.286)
            (xy 1.143 1.778)
            (xy 1.143 2.286)
            (xy 1.651 2.286)
            (xy 1.143 2.286)
            (xy 2.159 1.27)
          )
          (stroke (width 0.254) (type default))
          (fill (type none))
        )
        (polyline
          (pts
            (xy 2.159 2.54)
            (xy 2.159 2.032)
            (xy 2.159 2.54)
            (xy 2.667 2.54)
            (xy 2.159 2.54)
            (xy 3.048 1.651)
          )
          (stroke (width 0.254) (type default))
          (fill (type none))
        )
        (pin passive line (at 0 0 0) (length 0.635)
          (name "C" (effects (font (size 1.27 1.27))))
          (number "1" (effects (font (size 1.27 1.27))))
        )
        (pin passive line (at 5.08 0 180) (length 0.635)
          (name "A" (effects (font (size 1.27 1.27))))
          (number "2" (effects (font (size 1.27 1.27))))
        )
      )
    )
	(symbol "antmicroMechanicalParts:MP_Pad6mm_Drill3mm" (pin_names hide) (in_bom no) (on_board yes)
      (property "Reference" "MP" (at 20.32 -2.54 0)
        (effects (font (size 1.27 1.27) (thickness 0.15)) (justify left bottom))
      )
      (property "Value" "MP_Pad6mm_Drill3mm" (at 20.32 -5.08 0)
        (effects (font (size 1.27 1.27) (thickness 0.15)) (justify left bottom))
      )
      (property "Footprint" "antmicro-footprints:MP_Pad6mm_Drill3mm" (at 20.32 -7.62 0)
        (effects (font (size 1.27 1.27) (thickness 0.15)) (justify left bottom) hide)
      )
      (property "Datasheet" "" (at 16.84 -15.57 0)
        (effects (font (size 1.27 1.27) (thickness 0.15)) (justify left bottom) hide)
      )
      (property "Author" "Antmicro" (at 20.32 -10.16 0)
        (effects (font (size 1.27 1.27) (thickness 0.15)) (justify left bottom) hide)
      )
      (property "License" "Apache-2.0" (at 20.32 -12.7 0)
        (effects (font (size 1.27 1.27) (thickness 0.15)) (justify left bottom) hide)
      )
      (property "ki_keywords" "MECHANICAL" (at 0 0 0)
        (effects (font (size 1.27 1.27)) hide)
      )
      (property "ki_description" "Mechanical part" (at 0 0 0)
        (effects (font (size 1.27 1.27)) hide)
      )
      (symbol "MP_Pad6mm_Drill3mm_1_1"
        (circle (center 5.08 0) (radius 1.27)
          (stroke (width 0.254) (type default))
          (fill (type background))
        )
        (circle (center 5.08 0) (radius 2.54)
          (stroke (width 0.254) (type default))
          (fill (type background))
        )
        (pin passive line (at 0 0 0) (length 2.54)
          (name "~" (effects (font (size 1.27 1.27))))
          (number "1" (effects (font (size 1.27 1.27))))
        )
      )
    )
	(symbol "antmicroMechanicalParts:antmicro_logo" (in_bom no) (on_board yes)
      (property "Reference" "N" (at 15.24 -5.08 0)
        (effects (font (size 1.27 1.27) (thickness 0.15)) (justify left bottom))
      )
      (property "Value" "antmicro_logo" (at 15.24 -7.62 0)
        (effects (font (size 1.27 1.27) (thickness 0.15)) (justify left bottom))
      )
      (property "Footprint" "antmicro-footprints:antmicro-logo" (at 15.24 -10.16 0)
        (effects (font (size 1.27 1.27) (thickness 0.15)) (justify left bottom) hide)
      )
      (property "Datasheet" "" (at 15.24 -12.7 0)
        (effects (font (size 1.27 1.27) (thickness 0.15)) (justify left bottom) hide)
      )
      (property "MPN" "" (at 0 0 0)
        (effects (font (size 1.27 1.27)))
      )
      (property "Manufacturer" "" (at 15.24 -20.32 0)
        (effects (font (size 1.27 1.27) (thickness 0.15)) (justify left bottom) hide)
      )
      (property "Author" "Antmicro" (at 15.24 -15.24 0)
        (effects (font (size 1.27 1.27) (thickness 0.15)) (justify left bottom) hide)
      )
      (property "License" "Apache-2.0" (at 15.24 -17.78 0)
        (effects (font (size 1.27 1.27) (thickness 0.15)) (justify left bottom) hide)
      )
      (property "ki_description" "Mechanical part" (at 0 0 0)
        (effects (font (size 1.27 1.27)) hide)
      )
      (symbol "antmicro_logo_1_1"
        (text "Logo" (at 0 0 0)
          (effects (font (size 1.27 1.27) (thickness 0.15)) (justify left bottom))
        )
      )
    )
	(symbol "antmicroMemory:MX25L8006EM1I-12G" (in_bom yes) (on_board yes)
      (property "Reference" "U" (at 35.56 0 0)
        (effects (font (size 1.27 1.27) (thickness 0.15)) (justify left bottom))
      )
      (property "Value" "MX25L8006EM1I-12G" (at 35.56 -2.54 0)
        (effects (font (size 1.27 1.27) (thickness 0.15)) (justify left bottom) hide)
      )
      (property "Footprint" "antmicro-footprints:SOIC-8_3.9x4.9x1.75mm_P1.27mm" (at 35.56 -5.08 0)
        (effects (font (size 1.27 1.27) (thickness 0.15)) (justify left bottom) hide)
      )
      (property "Datasheet" "https://www.macronix.com/Lists/Datasheet/Attachments/8680/MX25L8006E,%203V,%208Mb,%20v1.6.pdf" (at 35.56 -7.62 0)
        (effects (font (size 1.27 1.27) (thickness 0.15)) (justify left bottom) hide)
      )
      (property "MPN" "MX25L8006EM1I-12G" (at 35.56 -10.16 0)
        (effects (font (size 1.27 1.27) (thickness 0.15)) (justify left bottom))
      )
      (property "Manufacturer" "Macronix" (at 35.56 -12.7 0)
        (effects (font (size 1.27 1.27) (thickness 0.15)) (justify left bottom) hide)
      )
      (property "Author" "Antmicro" (at 35.56 -15.24 0)
        (effects (font (size 1.27 1.27) (thickness 0.15)) (justify left bottom) hide)
      )
      (property "License" "Apache-2.0" (at 35.56 -17.78 0)
        (effects (font (size 1.27 1.27) (thickness 0.15)) (justify left bottom) hide)
      )
      (property "ki_keywords" "SMT, MEMORY, IC, FLASH" (at 0 0 0)
        (effects (font (size 1.27 1.27)) hide)
      )
      (property "ki_description" "FLASH - NOR Memory IC 8Mbit SPI 86 MHz 8-SOP" (at 0 0 0)
        (effects (font (size 1.27 1.27)) hide)
      )
      (symbol "MX25L8006EM1I-12G_0_1"
        (rectangle (start 2.54 2.54) (end 22.86 -13.97)
          (stroke (width 0.254) (type default))
          (fill (type background))
        )
      )
      (symbol "MX25L8006EM1I-12G_1_1"
        (pin input line (at 0 -12.7 0) (length 2.54)
          (name "~{CS}" (effects (font (size 1.27 1.27))))
          (number "1" (effects (font (size 1.27 1.27))))
        )
        (pin input line (at 0 -2.54 0) (length 2.54)
          (name "SO/IO1" (effects (font (size 1.27 1.27))))
          (number "2" (effects (font (size 1.27 1.27))))
        )
        (pin input line (at 0 -5.08 0) (length 2.54)
          (name "~{WP}" (effects (font (size 1.27 1.27))))
          (number "3" (effects (font (size 1.27 1.27))))
        )
        (pin power_in line (at 25.4 -10.16 180) (length 2.54)
          (name "GND" (effects (font (size 1.27 1.27))))
          (number "4" (effects (font (size 1.27 1.27))))
        )
        (pin input line (at 0 0 0) (length 2.54)
          (name "SI/IO0" (effects (font (size 1.27 1.27))))
          (number "5" (effects (font (size 1.27 1.27))))
        )
        (pin input line (at 0 -10.16 0) (length 2.54)
          (name "SCLK" (effects (font (size 1.27 1.27))))
          (number "6" (effects (font (size 1.27 1.27))))
        )
        (pin input line (at 0 -7.62 0) (length 2.54)
          (name "~{HOLD}" (effects (font (size 1.27 1.27))))
          (number "7" (effects (font (size 1.27 1.27))))
        )
        (pin power_in line (at 25.4 -1.27 180) (length 2.54)
          (name "VCC" (effects (font (size 1.27 1.27))))
          (number "8" (effects (font (size 1.27 1.27))))
        )
      )
    )
	(symbol "antmicroMemory:MX25L8006EM2I-12G" (in_bom yes) (on_board yes)
      (property "Reference" "U" (at 35.56 0 0)
        (effects (font (size 1.27 1.27) (thickness 0.15)) (justify left bottom))
      )
      (property "Value" "MX25L8006EM2I-12G" (at 35.56 -2.54 0)
        (effects (font (size 1.27 1.27) (thickness 0.15)) (justify left bottom) hide)
      )
      (property "Footprint" "antmicro-footprints:SOIC-8_5.3x5.3x2mm_P1.27mm" (at 35.56 -5.08 0)
        (effects (font (size 1.27 1.27) (thickness 0.15)) (justify left bottom) hide)
      )
      (property "Datasheet" "https://www.macronix.com/Lists/Datasheet/Attachments/8680/MX25L8006E,%203V,%208Mb,%20v1.6.pdf" (at 35.56 -7.62 0)
        (effects (font (size 1.27 1.27) (thickness 0.15)) (justify left bottom) hide)
      )
      (property "MPN" "MX25L8006EM2I-12G" (at 35.56 -10.16 0)
        (effects (font (size 1.27 1.27) (thickness 0.15)) (justify left bottom))
      )
      (property "Manufacturer" "Macronix" (at 35.56 -12.7 0)
        (effects (font (size 1.27 1.27) (thickness 0.15)) (justify left bottom) hide)
      )
      (property "Author" "Antmicro" (at 35.56 -15.24 0)
        (effects (font (size 1.27 1.27) (thickness 0.15)) (justify left bottom) hide)
      )
      (property "License" "Apache-2.0" (at 35.56 -17.78 0)
        (effects (font (size 1.27 1.27) (thickness 0.15)) (justify left bottom) hide)
      )
      (property "ki_keywords" "SMT, MEMORY, IC, FLASH, SPI" (at 0 0 0)
        (effects (font (size 1.27 1.27)) hide)
      )
      (property "ki_description" "FLASH - NOR Memory IC 8Mbit SPI 86 MHz 8-SOP" (at 0 0 0)
        (effects (font (size 1.27 1.27)) hide)
      )
      (symbol "MX25L8006EM2I-12G_0_1"
        (rectangle (start 2.54 2.54) (end 22.86 -13.97)
          (stroke (width 0.254) (type default))
          (fill (type background))
        )
      )
      (symbol "MX25L8006EM2I-12G_1_1"
        (pin input line (at 0 -12.7 0) (length 2.54)
          (name "~{CS}" (effects (font (size 1.27 1.27))))
          (number "1" (effects (font (size 1.27 1.27))))
        )
        (pin input line (at 0 -2.54 0) (length 2.54)
          (name "SO/IO1" (effects (font (size 1.27 1.27))))
          (number "2" (effects (font (size 1.27 1.27))))
        )
        (pin input line (at 0 -5.08 0) (length 2.54)
          (name "~{WP}" (effects (font (size 1.27 1.27))))
          (number "3" (effects (font (size 1.27 1.27))))
        )
        (pin power_in line (at 25.4 -10.16 180) (length 2.54)
          (name "GND" (effects (font (size 1.27 1.27))))
          (number "4" (effects (font (size 1.27 1.27))))
        )
        (pin input line (at 0 0 0) (length 2.54)
          (name "SI/IO0" (effects (font (size 1.27 1.27))))
          (number "5" (effects (font (size 1.27 1.27))))
        )
        (pin input line (at 0 -10.16 0) (length 2.54)
          (name "SCLK" (effects (font (size 1.27 1.27))))
          (number "6" (effects (font (size 1.27 1.27))))
        )
        (pin input line (at 0 -7.62 0) (length 2.54)
          (name "~{HOLD}" (effects (font (size 1.27 1.27))))
          (number "7" (effects (font (size 1.27 1.27))))
        )
        (pin power_in line (at 25.4 -1.27 180) (length 2.54)
          (name "VCC" (effects (font (size 1.27 1.27))))
          (number "8" (effects (font (size 1.27 1.27))))
        )
      )
    )
	(symbol "antmicroPMICORControllersIdealDiodes:DZDH0401DW" (in_bom yes) (on_board yes)
      (property "Reference" "Q" (at 30.48 -5.08 0)
        (effects (font (size 1.27 1.27) (thickness 0.15)) (justify left bottom))
      )
      (property "Value" "DZDH0401DW" (at 30.48 -7.62 0)
        (effects (font (size 1.27 1.27) (thickness 0.15)) (justify left bottom) hide)
      )
      (property "Footprint" "antmicro-footprints:SOT-363" (at 30.48 -10.16 0)
        (effects (font (size 1.27 1.27) (thickness 0.15)) (justify left bottom) hide)
      )
      (property "Datasheet" "https://www.mouser.com/datasheet/2/115/DIOD_S_A0011803041_1-2543705.pdf" (at 30.48 -12.7 0)
        (effects (font (size 1.27 1.27) (thickness 0.15)) (justify left bottom) hide)
      )
      (property "MPN" "DZDH0401DW" (at 30.48 -15.24 0)
        (effects (font (size 1.27 1.27) (thickness 0.15)) (justify left bottom))
      )
      (property "Manufacturer" "Diodes Incorporated" (at 30.48 -17.78 0)
        (effects (font (size 1.27 1.27) (thickness 0.15)) (justify left bottom) hide)
      )
      (property "Author" "Antmicro" (at 30.48 -20.32 0)
        (effects (font (size 1.27 1.27) (thickness 0.15)) (justify left bottom) hide)
      )
      (property "License" "Apache-2.0" (at 30.48 -22.86 0)
        (effects (font (size 1.27 1.27) (thickness 0.15)) (justify left bottom) hide)
      )
      (property "ki_keywords" "SMT, CONTROLLER, SEMICONDUCTOR, DIODE, PMOS" (at 0 0 0)
        (effects (font (size 1.27 1.27)) hide)
      )
      (property "ki_description" "OR Controller N+1 ORing Controller P-Channel 1:1 SOT-363" (at 0 0 0)
        (effects (font (size 1.27 1.27)) hide)
      )
      (symbol "DZDH0401DW_1_1"
        (rectangle (start 2.54 1.905) (end 13.97 -4.445)
          (stroke (width 0.254) (type default))
          (fill (type background))
        )
        (pin input line (at 0 -2.54 0) (length 2.54)
          (name "REF" (effects (font (size 1.27 1.27))))
          (number "2" (effects (font (size 1.27 1.27))))
        )
        (pin output line (at 16.51 -2.54 180) (length 2.54)
          (name "BIAS" (effects (font (size 1.27 1.27))))
          (number "3" (effects (font (size 1.27 1.27))))
        )
        (pin power_in line (at 16.51 0 180) (length 2.54)
          (name "S" (effects (font (size 1.27 1.27))))
          (number "4" (effects (font (size 1.27 1.27))))
        )
        (pin power_in line (at 0 0 0) (length 2.54)
          (name "D" (effects (font (size 1.27 1.27))))
          (number "6" (effects (font (size 1.27 1.27))))
        )
      )
    )
	(symbol "antmicroPciConnectors:PCIe_x4_Conn_EdgeMount_Open" (in_bom yes) (on_board yes)
      (property "Reference" "J" (at 48.26 -2.54 0)
        (effects (font (size 1.27 1.27) (thickness 0.15)) (justify left bottom))
      )
      (property "Value" "PCIe_x4_Conn_EdgeMount_Open" (at 48.26 -5.08 0)
        (effects (font (size 1.27 1.27) (thickness 0.15)) (justify left bottom) hide)
      )
      (property "Footprint" "antmicro-footprints:PCIE_TE_2-2387405-2" (at 48.26 -7.62 0)
        (effects (font (size 1.27 1.27) (thickness 0.15)) (justify left bottom) hide)
      )
      (property "Datasheet" "https://www.te.com/commerce/DocumentDelivery/DDEController?Action=showdoc&DocId=Customer+Drawing%7F2387405%7FA%7Fpdf%7FEnglish%7FENG_CD_2387405_A.pdf%7F2-2387405-2" (at 48.26 -10.16 0)
        (effects (font (size 1.27 1.27) (thickness 0.15)) (justify left bottom) hide)
      )
      (property "MPN" "2-2387405-2" (at 48.26 -12.7 0)
        (effects (font (size 1.27 1.27) (thickness 0.15)) (justify left bottom))
      )
      (property "Manufacturer" "TE Connectivity" (at 48.26 -15.24 0)
        (effects (font (size 1.27 1.27) (thickness 0.15)) (justify left bottom) hide)
      )
      (property "Author" "Antmicro" (at 48.26 -17.78 0)
        (effects (font (size 1.27 1.27) (thickness 0.15)) (justify left bottom) hide)
      )
      (property "License" "Apache-2.0" (at 48.26 -20.32 0)
        (effects (font (size 1.27 1.27) (thickness 0.15)) (justify left bottom) hide)
      )
      (property "ki_keywords" "SMT, PCIE, CONNECTOR" (at 0 0 0)
        (effects (font (size 1.27 1.27)) hide)
      )
      (property "ki_description" "64 Position Female Connector PCI Express™ Gold 0.039\" (1.00mm) Black" (at 0 0 0)
        (effects (font (size 1.27 1.27)) hide)
      )
      (symbol "PCIe_x4_Conn_EdgeMount_Open_0_1"
        (rectangle (start 3.81 2.54) (end 29.21 -83.82)
          (stroke (width 0.254) (type default))
          (fill (type background))
        )
      )
      (symbol "PCIe_x4_Conn_EdgeMount_Open_1_1"
        (pin passive line (at 33.02 0 180) (length 3.81)
          (name "PRSNT#1" (effects (font (size 1.27 1.27))))
          (number "A1" (effects (font (size 1.27 1.27))))
        )
        (pin passive line (at 33.02 -22.86 180) (length 3.81)
          (name "+3V3" (effects (font (size 1.27 1.27))))
          (number "A10" (effects (font (size 1.27 1.27))))
        )
        (pin passive line (at 33.02 -25.4 180) (length 3.81)
          (name "PWRGD" (effects (font (size 1.27 1.27))))
          (number "A11" (effects (font (size 1.27 1.27))))
        )
        (pin passive line (at 33.02 -30.48 180) (length 3.81)
          (name "GND" (effects (font (size 1.27 1.27))))
          (number "A12" (effects (font (size 1.27 1.27))))
        )
        (pin passive line (at 33.02 -33.02 180) (length 3.81)
          (name "REFCLK+" (effects (font (size 1.27 1.27))))
          (number "A13" (effects (font (size 1.27 1.27))))
        )
        (pin passive line (at 33.02 -35.56 180) (length 3.81)
          (name "REFCLK-" (effects (font (size 1.27 1.27))))
          (number "A14" (effects (font (size 1.27 1.27))))
        )
        (pin passive line (at 33.02 -38.1 180) (length 3.81)
          (name "GND" (effects (font (size 1.27 1.27))))
          (number "A15" (effects (font (size 1.27 1.27))))
        )
        (pin passive line (at 33.02 -40.64 180) (length 3.81)
          (name "HSIp(0)" (effects (font (size 1.27 1.27))))
          (number "A16" (effects (font (size 1.27 1.27))))
        )
        (pin passive line (at 33.02 -43.18 180) (length 3.81)
          (name "HSIn(0)" (effects (font (size 1.27 1.27))))
          (number "A17" (effects (font (size 1.27 1.27))))
        )
        (pin passive line (at 33.02 -45.72 180) (length 3.81)
          (name "GND" (effects (font (size 1.27 1.27))))
          (number "A18" (effects (font (size 1.27 1.27))))
        )
        (pin passive line (at 33.02 -48.26 180) (length 3.81)
          (name "RSVD" (effects (font (size 1.27 1.27))))
          (number "A19" (effects (font (size 1.27 1.27))))
        )
        (pin passive line (at 33.02 -2.54 180) (length 3.81)
          (name "+12V" (effects (font (size 1.27 1.27))))
          (number "A2" (effects (font (size 1.27 1.27))))
        )
        (pin passive line (at 33.02 -50.8 180) (length 3.81)
          (name "GND" (effects (font (size 1.27 1.27))))
          (number "A20" (effects (font (size 1.27 1.27))))
        )
        (pin passive line (at 33.02 -53.34 180) (length 3.81)
          (name "HSIp(1)" (effects (font (size 1.27 1.27))))
          (number "A21" (effects (font (size 1.27 1.27))))
        )
        (pin passive line (at 33.02 -55.88 180) (length 3.81)
          (name "HSIn(1)" (effects (font (size 1.27 1.27))))
          (number "A22" (effects (font (size 1.27 1.27))))
        )
        (pin passive line (at 33.02 -58.42 180) (length 3.81)
          (name "GND" (effects (font (size 1.27 1.27))))
          (number "A23" (effects (font (size 1.27 1.27))))
        )
        (pin passive line (at 33.02 -60.96 180) (length 3.81)
          (name "GND" (effects (font (size 1.27 1.27))))
          (number "A24" (effects (font (size 1.27 1.27))))
        )
        (pin passive line (at 33.02 -63.5 180) (length 3.81)
          (name "HSIp(2)" (effects (font (size 1.27 1.27))))
          (number "A25" (effects (font (size 1.27 1.27))))
        )
        (pin passive line (at 33.02 -66.04 180) (length 3.81)
          (name "HSIn(2)" (effects (font (size 1.27 1.27))))
          (number "A26" (effects (font (size 1.27 1.27))))
        )
        (pin passive line (at 33.02 -68.58 180) (length 3.81)
          (name "GND" (effects (font (size 1.27 1.27))))
          (number "A27" (effects (font (size 1.27 1.27))))
        )
        (pin input line (at 33.02 -71.12 180) (length 3.81)
          (name "GND" (effects (font (size 1.27 1.27))))
          (number "A28" (effects (font (size 1.27 1.27))))
        )
        (pin passive line (at 33.02 -73.66 180) (length 3.81)
          (name "HSIp(3)" (effects (font (size 1.27 1.27))))
          (number "A29" (effects (font (size 1.27 1.27))))
        )
        (pin passive line (at 33.02 -5.08 180) (length 3.81)
          (name "+12V" (effects (font (size 1.27 1.27))))
          (number "A3" (effects (font (size 1.27 1.27))))
        )
        (pin passive line (at 33.02 -76.2 180) (length 3.81)
          (name "HSIn(3)" (effects (font (size 1.27 1.27))))
          (number "A30" (effects (font (size 1.27 1.27))))
        )
        (pin passive line (at 33.02 -78.74 180) (length 3.81)
          (name "GND" (effects (font (size 1.27 1.27))))
          (number "A31" (effects (font (size 1.27 1.27))))
        )
        (pin passive line (at 33.02 -81.28 180) (length 3.81)
          (name "RSVD" (effects (font (size 1.27 1.27))))
          (number "A32" (effects (font (size 1.27 1.27))))
        )
        (pin passive line (at 33.02 -7.62 180) (length 3.81)
          (name "GND" (effects (font (size 1.27 1.27))))
          (number "A4" (effects (font (size 1.27 1.27))))
        )
        (pin passive line (at 33.02 -10.16 180) (length 3.81)
          (name "JTAG2" (effects (font (size 1.27 1.27))))
          (number "A5" (effects (font (size 1.27 1.27))))
        )
        (pin passive line (at 33.02 -12.7 180) (length 3.81)
          (name "JTAG3" (effects (font (size 1.27 1.27))))
          (number "A6" (effects (font (size 1.27 1.27))))
        )
        (pin passive line (at 33.02 -15.24 180) (length 3.81)
          (name "JTAG4" (effects (font (size 1.27 1.27))))
          (number "A7" (effects (font (size 1.27 1.27))))
        )
        (pin passive line (at 33.02 -17.78 180) (length 3.81)
          (name "JTAG5" (effects (font (size 1.27 1.27))))
          (number "A8" (effects (font (size 1.27 1.27))))
        )
        (pin passive line (at 33.02 -20.32 180) (length 3.81)
          (name "+3V3" (effects (font (size 1.27 1.27))))
          (number "A9" (effects (font (size 1.27 1.27))))
        )
        (pin passive line (at 0 0 0) (length 3.81)
          (name "+12V" (effects (font (size 1.27 1.27))))
          (number "B1" (effects (font (size 1.27 1.27))))
        )
        (pin passive line (at 0 -22.86 0) (length 3.81)
          (name "+3V3aux" (effects (font (size 1.27 1.27))))
          (number "B10" (effects (font (size 1.27 1.27))))
        )
        (pin passive line (at 0 -25.4 0) (length 3.81)
          (name "WAKE#" (effects (font (size 1.27 1.27))))
          (number "B11" (effects (font (size 1.27 1.27))))
        )
        (pin passive line (at 0 -30.48 0) (length 3.81)
          (name "RSVD" (effects (font (size 1.27 1.27))))
          (number "B12" (effects (font (size 1.27 1.27))))
        )
        (pin passive line (at 0 -33.02 0) (length 3.81)
          (name "GND" (effects (font (size 1.27 1.27))))
          (number "B13" (effects (font (size 1.27 1.27))))
        )
        (pin passive line (at 0 -35.56 0) (length 3.81)
          (name "HSOp(0)" (effects (font (size 1.27 1.27))))
          (number "B14" (effects (font (size 1.27 1.27))))
        )
        (pin passive line (at 0 -38.1 0) (length 3.81)
          (name "HSOn(0)" (effects (font (size 1.27 1.27))))
          (number "B15" (effects (font (size 1.27 1.27))))
        )
        (pin passive line (at 0 -40.64 0) (length 3.81)
          (name "GND" (effects (font (size 1.27 1.27))))
          (number "B16" (effects (font (size 1.27 1.27))))
        )
        (pin passive line (at 0 -43.18 0) (length 3.81)
          (name "PRSNT#2" (effects (font (size 1.27 1.27))))
          (number "B17" (effects (font (size 1.27 1.27))))
        )
        (pin passive line (at 0 -45.72 0) (length 3.81)
          (name "GND" (effects (font (size 1.27 1.27))))
          (number "B18" (effects (font (size 1.27 1.27))))
        )
        (pin passive line (at 0 -48.26 0) (length 3.81)
          (name "HSOp(1)" (effects (font (size 1.27 1.27))))
          (number "B19" (effects (font (size 1.27 1.27))))
        )
        (pin passive line (at 0 -2.54 0) (length 3.81)
          (name "+12V" (effects (font (size 1.27 1.27))))
          (number "B2" (effects (font (size 1.27 1.27))))
        )
        (pin passive line (at 0 -50.8 0) (length 3.81)
          (name "HSOn(1)" (effects (font (size 1.27 1.27))))
          (number "B20" (effects (font (size 1.27 1.27))))
        )
        (pin passive line (at 0 -53.34 0) (length 3.81)
          (name "GND" (effects (font (size 1.27 1.27))))
          (number "B21" (effects (font (size 1.27 1.27))))
        )
        (pin passive line (at 0 -55.88 0) (length 3.81)
          (name "GND" (effects (font (size 1.27 1.27))))
          (number "B22" (effects (font (size 1.27 1.27))))
        )
        (pin passive line (at 0 -58.42 0) (length 3.81)
          (name "HSOp(2)" (effects (font (size 1.27 1.27))))
          (number "B23" (effects (font (size 1.27 1.27))))
        )
        (pin passive line (at 0 -60.96 0) (length 3.81)
          (name "HSOn(2)" (effects (font (size 1.27 1.27))))
          (number "B24" (effects (font (size 1.27 1.27))))
        )
        (pin passive line (at 0 -63.5 0) (length 3.81)
          (name "GND" (effects (font (size 1.27 1.27))))
          (number "B25" (effects (font (size 1.27 1.27))))
        )
        (pin passive line (at 0 -66.04 0) (length 3.81)
          (name "GND" (effects (font (size 1.27 1.27))))
          (number "B26" (effects (font (size 1.27 1.27))))
        )
        (pin passive line (at 0 -68.58 0) (length 3.81)
          (name "HSOp(3)" (effects (font (size 1.27 1.27))))
          (number "B27" (effects (font (size 1.27 1.27))))
        )
        (pin passive line (at 0 -71.12 0) (length 3.81)
          (name "HSOn(3)" (effects (font (size 1.27 1.27))))
          (number "B28" (effects (font (size 1.27 1.27))))
        )
        (pin passive line (at 0 -73.66 0) (length 3.81)
          (name "GND" (effects (font (size 1.27 1.27))))
          (number "B29" (effects (font (size 1.27 1.27))))
        )
        (pin passive line (at 0 -5.08 0) (length 3.81)
          (name "+12V" (effects (font (size 1.27 1.27))))
          (number "B3" (effects (font (size 1.27 1.27))))
        )
        (pin passive line (at 0 -76.2 0) (length 3.81)
          (name "RSVD" (effects (font (size 1.27 1.27))))
          (number "B30" (effects (font (size 1.27 1.27))))
        )
        (pin passive line (at 0 -78.74 0) (length 3.81)
          (name "PRSNT#2" (effects (font (size 1.27 1.27))))
          (number "B31" (effects (font (size 1.27 1.27))))
        )
        (pin passive line (at 0 -81.28 0) (length 3.81)
          (name "GND" (effects (font (size 1.27 1.27))))
          (number "B32" (effects (font (size 1.27 1.27))))
        )
        (pin passive line (at 0 -7.62 0) (length 3.81)
          (name "GND" (effects (font (size 1.27 1.27))))
          (number "B4" (effects (font (size 1.27 1.27))))
        )
        (pin passive line (at 0 -10.16 0) (length 3.81)
          (name "SMCLK" (effects (font (size 1.27 1.27))))
          (number "B5" (effects (font (size 1.27 1.27))))
        )
        (pin passive line (at 0 -12.7 0) (length 3.81)
          (name "SMDAT" (effects (font (size 1.27 1.27))))
          (number "B6" (effects (font (size 1.27 1.27))))
        )
        (pin passive line (at 0 -15.24 0) (length 3.81)
          (name "GND" (effects (font (size 1.27 1.27))))
          (number "B7" (effects (font (size 1.27 1.27))))
        )
        (pin passive line (at 0 -17.78 0) (length 3.81)
          (name "+3V3" (effects (font (size 1.27 1.27))))
          (number "B8" (effects (font (size 1.27 1.27))))
        )
        (pin passive line (at 0 -20.32 0) (length 3.81)
          (name "JTAG1" (effects (font (size 1.27 1.27))))
          (number "B9" (effects (font (size 1.27 1.27))))
        )
      )
    )
	(symbol "antmicroResistors0402:R_0R_0402" (pin_numbers hide) (pin_names hide) (in_bom yes) (on_board yes)
      (property "Reference" "R" (at 20.32 -5.08 0)
        (effects (font (size 1.27 1.27) (thickness 0.15)) (justify left bottom))
      )
      (property "Value" "R_0R_0402" (at 20.32 -12.7 0)
        (effects (font (size 1.27 1.27) (thickness 0.15)) (justify left bottom) hide)
      )
      (property "Footprint" "antmicro-footprints:R_0402_1005Metric" (at 20.32 -15.24 0)
        (effects (font (size 1.27 1.27) (thickness 0.15)) (justify left bottom) hide)
      )
      (property "Datasheet" "https://industrial.panasonic.com/cdbs/www-data/pdf/RDA0000/AOA0000C301.pdf" (at 20.32 -17.78 0)
        (effects (font (size 1.27 1.27) (thickness 0.15)) (justify left bottom) hide)
      )
      (property "MPN" "ERJ2GE0R00X" (at 20.32 -20.32 0)
        (effects (font (size 1.27 1.27) (thickness 0.15)) (justify left bottom) hide)
      )
      (property "Manufacturer" "Panasonic" (at 20.32 -22.86 0)
        (effects (font (size 1.27 1.27) (thickness 0.15)) (justify left bottom) hide)
      )
      (property "License" "Apache-2.0" (at 20.32 -25.4 0)
        (effects (font (size 1.27 1.27) (thickness 0.15)) (justify left bottom) hide)
      )
      (property "Author" "Antmicro" (at 20.32 -27.94 0)
        (effects (font (size 1.27 1.27) (thickness 0.15)) (justify left bottom) hide)
      )
      (property "Val" "0R" (at 20.32 -7.62 0)
        (effects (font (size 1.27 1.27) (thickness 0.15)) (justify left bottom))
      )
      (property "Tolerance" "~" (at 20.32 -10.16 0)
        (effects (font (size 1.27 1.27)) (justify left bottom) hide)
      )
      (property "Current" "1A" (at 20.32 -30.48 0)
        (effects (font (size 1.27 1.27) (thickness 0.15)) (justify left bottom) hide)
      )
      (property "ki_keywords" "0402, SMT, RESISTOR, PASSIVE" (at 0 0 0)
        (effects (font (size 1.27 1.27)) hide)
      )
      (property "ki_description" "SMD Chip Resistor, Jumper, 0 ohm, 100 mW, 0402 [1005 Metric], Thick Film, General Purpose" (at 0 0 0)
        (effects (font (size 1.27 1.27)) hide)
      )
      (symbol "R_0R_0402_0_1"
        (rectangle (start 0.635 0.889) (end 4.445 -0.889)
          (stroke (width 0.254) (type default))
          (fill (type none))
        )
      )
      (symbol "R_0R_0402_1_1"
        (pin passive line (at 0 0 0) (length 0.635)
          (name "~" (effects (font (size 1.27 1.27))))
          (number "1" (effects (font (size 1.27 1.27))))
        )
        (pin passive line (at 5.08 0 180) (length 0.635)
          (name "~" (effects (font (size 1.27 1.27))))
          (number "2" (effects (font (size 1.27 1.27))))
        )
      )
    )
	(symbol "antmicroResistors0402:R_100R_0402" (pin_numbers hide) (pin_names hide) (in_bom yes) (on_board yes)
      (property "Reference" "R" (at 20.32 -5.08 0)
        (effects (font (size 1.27 1.27) (thickness 0.15)) (justify left bottom))
      )
      (property "Value" "R_100R_0402" (at 20.32 -12.7 0)
        (effects (font (size 1.27 1.27) (thickness 0.15)) (justify left bottom) hide)
      )
      (property "Footprint" "antmicro-footprints:R_0402_1005Metric" (at 20.32 -15.24 0)
        (effects (font (size 1.27 1.27) (thickness 0.15)) (justify left bottom) hide)
      )
      (property "Datasheet" "https://www.bourns.com/docs/product-datasheets/cr.pdf" (at 20.32 -17.78 0)
        (effects (font (size 1.27 1.27) (thickness 0.15)) (justify left bottom) hide)
      )
      (property "MPN" "CR0402-FX-1000GLF" (at 20.32 -20.32 0)
        (effects (font (size 1.27 1.27) (thickness 0.15)) (justify left bottom) hide)
      )
      (property "Manufacturer" "Bourns" (at 20.32 -22.86 0)
        (effects (font (size 1.27 1.27) (thickness 0.15)) (justify left bottom) hide)
      )
      (property "License" "Apache-2.0" (at 20.32 -25.4 0)
        (effects (font (size 1.27 1.27) (thickness 0.15)) (justify left bottom) hide)
      )
      (property "Author" "Antmicro" (at 20.32 -27.94 0)
        (effects (font (size 1.27 1.27) (thickness 0.15)) (justify left bottom) hide)
      )
      (property "Val" "100R" (at 20.32 -7.62 0)
        (effects (font (size 1.27 1.27) (thickness 0.15)) (justify left bottom))
      )
      (property "Tolerance" "1%" (at 20.32 -10.16 0)
        (effects (font (size 1.27 1.27)) (justify left bottom) hide)
      )
      (property "ki_keywords" "0402, SMT, RESISTOR, PASSIVE" (at 0 0 0)
        (effects (font (size 1.27 1.27)) hide)
      )
      (property "ki_description" "SMD Chip Resistor, 100 ohm, ± 1%, 62.5 mW, 0402 [1005 Metric], Thick Film, General Purpose" (at 0 0 0)
        (effects (font (size 1.27 1.27)) hide)
      )
      (symbol "R_100R_0402_0_1"
        (rectangle (start 0.635 0.889) (end 4.445 -0.889)
          (stroke (width 0.254) (type default))
          (fill (type none))
        )
      )
      (symbol "R_100R_0402_1_1"
        (pin passive line (at 0 0 0) (length 0.635)
          (name "~" (effects (font (size 1.27 1.27))))
          (number "1" (effects (font (size 1.27 1.27))))
        )
        (pin passive line (at 5.08 0 180) (length 0.635)
          (name "~" (effects (font (size 1.27 1.27))))
          (number "2" (effects (font (size 1.27 1.27))))
        )
      )
    )
	(symbol "antmicroResistors0402:R_100k_0402" (pin_numbers hide) (pin_names hide) (in_bom yes) (on_board yes)
      (property "Reference" "R" (at 20.32 -5.08 0)
        (effects (font (size 1.27 1.27) (thickness 0.15)) (justify left bottom))
      )
      (property "Value" "R_100k_0402" (at 20.32 -12.7 0)
        (effects (font (size 1.27 1.27) (thickness 0.15)) (justify left bottom) hide)
      )
      (property "Footprint" "antmicro-footprints:R_0402_1005Metric" (at 20.32 -15.24 0)
        (effects (font (size 1.27 1.27) (thickness 0.15)) (justify left bottom) hide)
      )
      (property "Datasheet" "https://www.bourns.com/docs/product-datasheets/cr.pdf" (at 20.32 -17.78 0)
        (effects (font (size 1.27 1.27) (thickness 0.15)) (justify left bottom) hide)
      )
      (property "MPN" "CR0402-FX-1003GLF" (at 20.32 -20.32 0)
        (effects (font (size 1.27 1.27) (thickness 0.15)) (justify left bottom) hide)
      )
      (property "Manufacturer" "Bourns" (at 20.32 -22.86 0)
        (effects (font (size 1.27 1.27) (thickness 0.15)) (justify left bottom) hide)
      )
      (property "License" "Apache-2.0" (at 20.32 -25.4 0)
        (effects (font (size 1.27 1.27) (thickness 0.15)) (justify left bottom) hide)
      )
      (property "Author" "Antmicro" (at 20.32 -27.94 0)
        (effects (font (size 1.27 1.27) (thickness 0.15)) (justify left bottom) hide)
      )
      (property "Val" "100k" (at 20.32 -7.62 0)
        (effects (font (size 1.27 1.27) (thickness 0.15)) (justify left bottom))
      )
      (property "Tolerance" "1%" (at 20.32 -10.16 0)
        (effects (font (size 1.27 1.27)) (justify left bottom) hide)
      )
      (property "ki_keywords" "0402, SMT, RESISTOR, PASSIVE" (at 0 0 0)
        (effects (font (size 1.27 1.27)) hide)
      )
      (property "ki_description" "SMD Chip Resistor, 100 kohm, ± 1%, 62.5 mW, 0402 [1005 Metric], Thick Film, General Purpose" (at 0 0 0)
        (effects (font (size 1.27 1.27)) hide)
      )
      (symbol "R_100k_0402_0_1"
        (rectangle (start 0.635 0.889) (end 4.445 -0.889)
          (stroke (width 0.254) (type default))
          (fill (type none))
        )
      )
      (symbol "R_100k_0402_1_1"
        (pin passive line (at 0 0 0) (length 0.635)
          (name "~" (effects (font (size 1.27 1.27))))
          (number "1" (effects (font (size 1.27 1.27))))
        )
        (pin passive line (at 5.08 0 180) (length 0.635)
          (name "~" (effects (font (size 1.27 1.27))))
          (number "2" (effects (font (size 1.27 1.27))))
        )
      )
    )
	(symbol "antmicroResistors0402:R_100k_0402_10" (pin_numbers hide) (pin_names hide) (in_bom yes) (on_board yes)
      (property "Reference" "R" (at 20.32 -5.08 0)
        (effects (font (size 1.27 1.27) (thickness 0.15)) (justify left bottom))
      )
      (property "Value" "R_100k_0402_10" (at 20.32 -12.7 0)
        (effects (font (size 1.27 1.27) (thickness 0.15)) (justify left bottom) hide)
      )
      (property "Footprint" "antmicro-footprints:R_0402_1005Metric" (at 20.32 -15.24 0)
        (effects (font (size 1.27 1.27) (thickness 0.15)) (justify left bottom) hide)
      )
      (property "Datasheet" "https://www.bourns.com/docs/product-datasheets/cr.pdf" (at 20.32 -17.78 0)
        (effects (font (size 1.27 1.27) (thickness 0.15)) (justify left bottom) hide)
      )
      (property "MPN" "CR0402-FX-1003GLF" (at 20.32 -20.32 0)
        (effects (font (size 1.27 1.27) (thickness 0.15)) (justify left bottom) hide)
      )
      (property "Manufacturer" "Bourns" (at 20.32 -22.86 0)
        (effects (font (size 1.27 1.27) (thickness 0.15)) (justify left bottom) hide)
      )
      (property "License" "Apache-2.0" (at 20.32 -25.4 0)
        (effects (font (size 1.27 1.27) (thickness 0.15)) (justify left bottom) hide)
      )
      (property "Author" "Antmicro" (at 20.32 -27.94 0)
        (effects (font (size 1.27 1.27) (thickness 0.15)) (justify left bottom) hide)
      )
      (property "Val" "100k" (at 20.32 -7.62 0)
        (effects (font (size 1.27 1.27) (thickness 0.15)) (justify left bottom))
      )
      (property "Tolerance" "1%" (at 20.32 -10.16 0)
        (effects (font (size 1.27 1.27)) (justify left bottom) hide)
      )
      (property "ki_description" "100k resistor in 0402 package with 1% tolerance" (at 0 0 0)
        (effects (font (size 1.27 1.27)) hide)
      )
      (symbol "R_100k_0402_10_0_1"
        (rectangle (start 0.635 0.889) (end 4.445 -0.889)
          (stroke (width 0.254) (type default))
          (fill (type none))
        )
      )
      (symbol "R_100k_0402_10_1_1"
        (pin passive line (at 0 0 0) (length 0.635)
          (name "~" (effects (font (size 1.27 1.27))))
          (number "1" (effects (font (size 1.27 1.27))))
        )
        (pin passive line (at 5.08 0 180) (length 0.635)
          (name "~" (effects (font (size 1.27 1.27))))
          (number "2" (effects (font (size 1.27 1.27))))
        )
      )
    )
	(symbol "antmicroResistors0402:R_100k_0402_11" (pin_numbers hide) (pin_names hide) (in_bom yes) (on_board yes)
      (property "Reference" "R" (at 20.32 -5.08 0)
        (effects (font (size 1.27 1.27) (thickness 0.15)) (justify left bottom))
      )
      (property "Value" "R_100k_0402_11" (at 20.32 -12.7 0)
        (effects (font (size 1.27 1.27) (thickness 0.15)) (justify left bottom) hide)
      )
      (property "Footprint" "antmicro-footprints:R_0402_1005Metric" (at 20.32 -15.24 0)
        (effects (font (size 1.27 1.27) (thickness 0.15)) (justify left bottom) hide)
      )
      (property "Datasheet" "https://www.bourns.com/docs/product-datasheets/cr.pdf" (at 20.32 -17.78 0)
        (effects (font (size 1.27 1.27) (thickness 0.15)) (justify left bottom) hide)
      )
      (property "MPN" "CR0402-FX-1003GLF" (at 20.32 -20.32 0)
        (effects (font (size 1.27 1.27) (thickness 0.15)) (justify left bottom) hide)
      )
      (property "Manufacturer" "Bourns" (at 20.32 -22.86 0)
        (effects (font (size 1.27 1.27) (thickness 0.15)) (justify left bottom) hide)
      )
      (property "License" "Apache-2.0" (at 20.32 -25.4 0)
        (effects (font (size 1.27 1.27) (thickness 0.15)) (justify left bottom) hide)
      )
      (property "Author" "Antmicro" (at 20.32 -27.94 0)
        (effects (font (size 1.27 1.27) (thickness 0.15)) (justify left bottom) hide)
      )
      (property "Val" "100k" (at 20.32 -7.62 0)
        (effects (font (size 1.27 1.27) (thickness 0.15)) (justify left bottom))
      )
      (property "Tolerance" "1%" (at 20.32 -10.16 0)
        (effects (font (size 1.27 1.27)) (justify left bottom) hide)
      )
      (property "ki_description" "100k resistor in 0402 package with 1% tolerance" (at 0 0 0)
        (effects (font (size 1.27 1.27)) hide)
      )
      (symbol "R_100k_0402_11_0_1"
        (rectangle (start 0.635 0.889) (end 4.445 -0.889)
          (stroke (width 0.254) (type default))
          (fill (type none))
        )
      )
      (symbol "R_100k_0402_11_1_1"
        (pin passive line (at 0 0 0) (length 0.635)
          (name "~" (effects (font (size 1.27 1.27))))
          (number "1" (effects (font (size 1.27 1.27))))
        )
        (pin passive line (at 5.08 0 180) (length 0.635)
          (name "~" (effects (font (size 1.27 1.27))))
          (number "2" (effects (font (size 1.27 1.27))))
        )
      )
    )
	(symbol "antmicroResistors0402:R_100k_0402_12" (pin_numbers hide) (pin_names hide) (in_bom yes) (on_board yes)
      (property "Reference" "R" (at 20.32 -5.08 0)
        (effects (font (size 1.27 1.27) (thickness 0.15)) (justify left bottom))
      )
      (property "Value" "R_100k_0402_12" (at 20.32 -12.7 0)
        (effects (font (size 1.27 1.27) (thickness 0.15)) (justify left bottom) hide)
      )
      (property "Footprint" "antmicro-footprints:R_0402_1005Metric" (at 20.32 -15.24 0)
        (effects (font (size 1.27 1.27) (thickness 0.15)) (justify left bottom) hide)
      )
      (property "Datasheet" "https://www.bourns.com/docs/product-datasheets/cr.pdf" (at 20.32 -17.78 0)
        (effects (font (size 1.27 1.27) (thickness 0.15)) (justify left bottom) hide)
      )
      (property "MPN" "CR0402-FX-1003GLF" (at 20.32 -20.32 0)
        (effects (font (size 1.27 1.27) (thickness 0.15)) (justify left bottom) hide)
      )
      (property "Manufacturer" "Bourns" (at 20.32 -22.86 0)
        (effects (font (size 1.27 1.27) (thickness 0.15)) (justify left bottom) hide)
      )
      (property "License" "Apache-2.0" (at 20.32 -25.4 0)
        (effects (font (size 1.27 1.27) (thickness 0.15)) (justify left bottom) hide)
      )
      (property "Author" "Antmicro" (at 20.32 -27.94 0)
        (effects (font (size 1.27 1.27) (thickness 0.15)) (justify left bottom) hide)
      )
      (property "Val" "100k" (at 20.32 -7.62 0)
        (effects (font (size 1.27 1.27) (thickness 0.15)) (justify left bottom))
      )
      (property "Tolerance" "1%" (at 20.32 -10.16 0)
        (effects (font (size 1.27 1.27)) (justify left bottom) hide)
      )
      (property "ki_description" "100k resistor in 0402 package with 1% tolerance" (at 0 0 0)
        (effects (font (size 1.27 1.27)) hide)
      )
      (symbol "R_100k_0402_12_0_1"
        (rectangle (start 0.635 0.889) (end 4.445 -0.889)
          (stroke (width 0.254) (type default))
          (fill (type none))
        )
      )
      (symbol "R_100k_0402_12_1_1"
        (pin passive line (at 0 0 0) (length 0.635)
          (name "~" (effects (font (size 1.27 1.27))))
          (number "1" (effects (font (size 1.27 1.27))))
        )
        (pin passive line (at 5.08 0 180) (length 0.635)
          (name "~" (effects (font (size 1.27 1.27))))
          (number "2" (effects (font (size 1.27 1.27))))
        )
      )
    )
	(symbol "antmicroResistors0402:R_10k_0402" (pin_numbers hide) (pin_names hide) (in_bom yes) (on_board yes)
      (property "Reference" "R" (at 20.32 -5.08 0)
        (effects (font (size 1.27 1.27) (thickness 0.15)) (justify left bottom))
      )
      (property "Value" "R_10k_0402" (at 20.32 -12.7 0)
        (effects (font (size 1.27 1.27) (thickness 0.15)) (justify left bottom) hide)
      )
      (property "Footprint" "antmicro-footprints:R_0402_1005Metric" (at 20.32 -15.24 0)
        (effects (font (size 1.27 1.27) (thickness 0.15)) (justify left bottom) hide)
      )
      (property "Datasheet" "https://www.bourns.com/docs/product-datasheets/cr.pdf" (at 20.32 -17.78 0)
        (effects (font (size 1.27 1.27) (thickness 0.15)) (justify left bottom) hide)
      )
      (property "MPN" "CR0402-FX-1002GLF" (at 20.32 -20.32 0)
        (effects (font (size 1.27 1.27) (thickness 0.15)) (justify left bottom) hide)
      )
      (property "Manufacturer" "Bourns" (at 20.32 -22.86 0)
        (effects (font (size 1.27 1.27) (thickness 0.15)) (justify left bottom) hide)
      )
      (property "License" "Apache-2.0" (at 20.32 -25.4 0)
        (effects (font (size 1.27 1.27) (thickness 0.15)) (justify left bottom) hide)
      )
      (property "Author" "Antmicro" (at 20.32 -27.94 0)
        (effects (font (size 1.27 1.27) (thickness 0.15)) (justify left bottom) hide)
      )
      (property "Val" "10k" (at 20.32 -7.62 0)
        (effects (font (size 1.27 1.27) (thickness 0.15)) (justify left bottom))
      )
      (property "Tolerance" "1%" (at 20.32 -10.16 0)
        (effects (font (size 1.27 1.27)) (justify left bottom) hide)
      )
      (property "ki_keywords" "0402, SMT, RESISTOR, PASSIVE" (at 0 0 0)
        (effects (font (size 1.27 1.27)) hide)
      )
      (property "ki_description" "SMD Chip Resistor, 10 kohm, ± 1%, 62.5 mW, 0402 [1005 Metric], Thick Film, General Purpose" (at 0 0 0)
        (effects (font (size 1.27 1.27)) hide)
      )
      (symbol "R_10k_0402_0_1"
        (rectangle (start 0.635 0.889) (end 4.445 -0.889)
          (stroke (width 0.254) (type default))
          (fill (type none))
        )
      )
      (symbol "R_10k_0402_1_1"
        (pin passive line (at 0 0 0) (length 0.635)
          (name "~" (effects (font (size 1.27 1.27))))
          (number "1" (effects (font (size 1.27 1.27))))
        )
        (pin passive line (at 5.08 0 180) (length 0.635)
          (name "~" (effects (font (size 1.27 1.27))))
          (number "2" (effects (font (size 1.27 1.27))))
        )
      )
    )
	(symbol "antmicroResistors0402:R_10k_0402_10" (pin_numbers hide) (pin_names hide) (in_bom yes) (on_board yes)
      (property "Reference" "R" (at 20.32 -5.08 0)
        (effects (font (size 1.27 1.27) (thickness 0.15)) (justify left bottom))
      )
      (property "Value" "R_10k_0402_10" (at 20.32 -12.7 0)
        (effects (font (size 1.27 1.27) (thickness 0.15)) (justify left bottom) hide)
      )
      (property "Footprint" "antmicro-footprints:R_0402_1005Metric" (at 20.32 -15.24 0)
        (effects (font (size 1.27 1.27) (thickness 0.15)) (justify left bottom) hide)
      )
      (property "Datasheet" "https://www.bourns.com/docs/product-datasheets/cr.pdf" (at 20.32 -17.78 0)
        (effects (font (size 1.27 1.27) (thickness 0.15)) (justify left bottom) hide)
      )
      (property "MPN" "CR0402-FX-1002GLF" (at 20.32 -20.32 0)
        (effects (font (size 1.27 1.27) (thickness 0.15)) (justify left bottom) hide)
      )
      (property "Manufacturer" "Bourns" (at 20.32 -22.86 0)
        (effects (font (size 1.27 1.27) (thickness 0.15)) (justify left bottom) hide)
      )
      (property "License" "Apache-2.0" (at 20.32 -25.4 0)
        (effects (font (size 1.27 1.27) (thickness 0.15)) (justify left bottom) hide)
      )
      (property "Author" "Antmicro" (at 20.32 -27.94 0)
        (effects (font (size 1.27 1.27) (thickness 0.15)) (justify left bottom) hide)
      )
      (property "Val" "10k" (at 20.32 -7.62 0)
        (effects (font (size 1.27 1.27) (thickness 0.15)) (justify left bottom))
      )
      (property "Tolerance" "1%" (at 20.32 -10.16 0)
        (effects (font (size 1.27 1.27)) (justify left bottom) hide)
      )
      (property "ki_description" "10k resistor in 0402 package with 1% tolerance" (at 0 0 0)
        (effects (font (size 1.27 1.27)) hide)
      )
      (symbol "R_10k_0402_10_0_1"
        (rectangle (start 0.635 0.889) (end 4.445 -0.889)
          (stroke (width 0.254) (type default))
          (fill (type none))
        )
      )
      (symbol "R_10k_0402_10_1_1"
        (pin passive line (at 0 0 0) (length 0.635)
          (name "~" (effects (font (size 1.27 1.27))))
          (number "1" (effects (font (size 1.27 1.27))))
        )
        (pin passive line (at 5.08 0 180) (length 0.635)
          (name "~" (effects (font (size 1.27 1.27))))
          (number "2" (effects (font (size 1.27 1.27))))
        )
      )
    )
	(symbol "antmicroResistors0402:R_10k_0402_11" (pin_numbers hide) (pin_names hide) (in_bom yes) (on_board yes)
      (property "Reference" "R" (at 20.32 -5.08 0)
        (effects (font (size 1.27 1.27) (thickness 0.15)) (justify left bottom))
      )
      (property "Value" "R_10k_0402_11" (at 20.32 -12.7 0)
        (effects (font (size 1.27 1.27) (thickness 0.15)) (justify left bottom) hide)
      )
      (property "Footprint" "antmicro-footprints:R_0402_1005Metric" (at 20.32 -15.24 0)
        (effects (font (size 1.27 1.27) (thickness 0.15)) (justify left bottom) hide)
      )
      (property "Datasheet" "https://www.bourns.com/docs/product-datasheets/cr.pdf" (at 20.32 -17.78 0)
        (effects (font (size 1.27 1.27) (thickness 0.15)) (justify left bottom) hide)
      )
      (property "MPN" "CR0402-FX-1002GLF" (at 20.32 -20.32 0)
        (effects (font (size 1.27 1.27) (thickness 0.15)) (justify left bottom) hide)
      )
      (property "Manufacturer" "Bourns" (at 20.32 -22.86 0)
        (effects (font (size 1.27 1.27) (thickness 0.15)) (justify left bottom) hide)
      )
      (property "License" "Apache-2.0" (at 20.32 -25.4 0)
        (effects (font (size 1.27 1.27) (thickness 0.15)) (justify left bottom) hide)
      )
      (property "Author" "Antmicro" (at 20.32 -27.94 0)
        (effects (font (size 1.27 1.27) (thickness 0.15)) (justify left bottom) hide)
      )
      (property "Val" "10k" (at 20.32 -7.62 0)
        (effects (font (size 1.27 1.27) (thickness 0.15)) (justify left bottom))
      )
      (property "Tolerance" "1%" (at 20.32 -10.16 0)
        (effects (font (size 1.27 1.27)) (justify left bottom) hide)
      )
      (property "ki_description" "10k resistor in 0402 package with 1% tolerance" (at 0 0 0)
        (effects (font (size 1.27 1.27)) hide)
      )
      (symbol "R_10k_0402_11_0_1"
        (rectangle (start 0.635 0.889) (end 4.445 -0.889)
          (stroke (width 0.254) (type default))
          (fill (type none))
        )
      )
      (symbol "R_10k_0402_11_1_1"
        (pin passive line (at 0 0 0) (length 0.635)
          (name "~" (effects (font (size 1.27 1.27))))
          (number "1" (effects (font (size 1.27 1.27))))
        )
        (pin passive line (at 5.08 0 180) (length 0.635)
          (name "~" (effects (font (size 1.27 1.27))))
          (number "2" (effects (font (size 1.27 1.27))))
        )
      )
    )
	(symbol "antmicroResistors0402:R_10k_0402_12" (pin_numbers hide) (pin_names hide) (in_bom yes) (on_board yes)
      (property "Reference" "R" (at 20.32 -5.08 0)
        (effects (font (size 1.27 1.27) (thickness 0.15)) (justify left bottom))
      )
      (property "Value" "R_10k_0402_12" (at 20.32 -12.7 0)
        (effects (font (size 1.27 1.27) (thickness 0.15)) (justify left bottom) hide)
      )
      (property "Footprint" "antmicro-footprints:R_0402_1005Metric" (at 20.32 -15.24 0)
        (effects (font (size 1.27 1.27) (thickness 0.15)) (justify left bottom) hide)
      )
      (property "Datasheet" "https://www.bourns.com/docs/product-datasheets/cr.pdf" (at 20.32 -17.78 0)
        (effects (font (size 1.27 1.27) (thickness 0.15)) (justify left bottom) hide)
      )
      (property "MPN" "CR0402-FX-1002GLF" (at 20.32 -20.32 0)
        (effects (font (size 1.27 1.27) (thickness 0.15)) (justify left bottom) hide)
      )
      (property "Manufacturer" "Bourns" (at 20.32 -22.86 0)
        (effects (font (size 1.27 1.27) (thickness 0.15)) (justify left bottom) hide)
      )
      (property "License" "Apache-2.0" (at 20.32 -25.4 0)
        (effects (font (size 1.27 1.27) (thickness 0.15)) (justify left bottom) hide)
      )
      (property "Author" "Antmicro" (at 20.32 -27.94 0)
        (effects (font (size 1.27 1.27) (thickness 0.15)) (justify left bottom) hide)
      )
      (property "Val" "10k" (at 20.32 -7.62 0)
        (effects (font (size 1.27 1.27) (thickness 0.15)) (justify left bottom))
      )
      (property "Tolerance" "1%" (at 20.32 -10.16 0)
        (effects (font (size 1.27 1.27)) (justify left bottom) hide)
      )
      (property "ki_description" "10k resistor in 0402 package with 1% tolerance" (at 0 0 0)
        (effects (font (size 1.27 1.27)) hide)
      )
      (symbol "R_10k_0402_12_0_1"
        (rectangle (start 0.635 0.889) (end 4.445 -0.889)
          (stroke (width 0.254) (type default))
          (fill (type none))
        )
      )
      (symbol "R_10k_0402_12_1_1"
        (pin passive line (at 0 0 0) (length 0.635)
          (name "~" (effects (font (size 1.27 1.27))))
          (number "1" (effects (font (size 1.27 1.27))))
        )
        (pin passive line (at 5.08 0 180) (length 0.635)
          (name "~" (effects (font (size 1.27 1.27))))
          (number "2" (effects (font (size 1.27 1.27))))
        )
      )
    )
	(symbol "antmicroResistors0402:R_10k_0402_13" (pin_numbers hide) (pin_names hide) (in_bom yes) (on_board yes)
      (property "Reference" "R" (at 20.32 -5.08 0)
        (effects (font (size 1.27 1.27) (thickness 0.15)) (justify left bottom))
      )
      (property "Value" "R_10k_0402_13" (at 20.32 -12.7 0)
        (effects (font (size 1.27 1.27) (thickness 0.15)) (justify left bottom) hide)
      )
      (property "Footprint" "antmicro-footprints:R_0402_1005Metric" (at 20.32 -15.24 0)
        (effects (font (size 1.27 1.27) (thickness 0.15)) (justify left bottom) hide)
      )
      (property "Datasheet" "https://www.bourns.com/docs/product-datasheets/cr.pdf" (at 20.32 -17.78 0)
        (effects (font (size 1.27 1.27) (thickness 0.15)) (justify left bottom) hide)
      )
      (property "MPN" "CR0402-FX-1002GLF" (at 20.32 -20.32 0)
        (effects (font (size 1.27 1.27) (thickness 0.15)) (justify left bottom) hide)
      )
      (property "Manufacturer" "Bourns" (at 20.32 -22.86 0)
        (effects (font (size 1.27 1.27) (thickness 0.15)) (justify left bottom) hide)
      )
      (property "License" "Apache-2.0" (at 20.32 -25.4 0)
        (effects (font (size 1.27 1.27) (thickness 0.15)) (justify left bottom) hide)
      )
      (property "Author" "Antmicro" (at 20.32 -27.94 0)
        (effects (font (size 1.27 1.27) (thickness 0.15)) (justify left bottom) hide)
      )
      (property "Val" "10k" (at 20.32 -7.62 0)
        (effects (font (size 1.27 1.27) (thickness 0.15)) (justify left bottom))
      )
      (property "Tolerance" "1%" (at 20.32 -10.16 0)
        (effects (font (size 1.27 1.27)) (justify left bottom) hide)
      )
      (property "ki_description" "10k resistor in 0402 package with 1% tolerance" (at 0 0 0)
        (effects (font (size 1.27 1.27)) hide)
      )
      (symbol "R_10k_0402_13_0_1"
        (rectangle (start 0.635 0.889) (end 4.445 -0.889)
          (stroke (width 0.254) (type default))
          (fill (type none))
        )
      )
      (symbol "R_10k_0402_13_1_1"
        (pin passive line (at 0 0 0) (length 0.635)
          (name "~" (effects (font (size 1.27 1.27))))
          (number "1" (effects (font (size 1.27 1.27))))
        )
        (pin passive line (at 5.08 0 180) (length 0.635)
          (name "~" (effects (font (size 1.27 1.27))))
          (number "2" (effects (font (size 1.27 1.27))))
        )
      )
    )
	(symbol "antmicroResistors0402:R_110k_0402" (pin_numbers hide) (pin_names hide) (in_bom yes) (on_board yes)
      (property "Reference" "R" (at 20.32 -5.08 0)
        (effects (font (size 1.27 1.27) (thickness 0.15)) (justify left bottom))
      )
      (property "Value" "R_110k_0402" (at 20.32 -12.7 0)
        (effects (font (size 1.27 1.27) (thickness 0.15)) (justify left bottom) hide)
      )
      (property "Footprint" "antmicro-footprints:R_0402_1005Metric" (at 20.32 -15.24 0)
        (effects (font (size 1.27 1.27) (thickness 0.15)) (justify left bottom) hide)
      )
      (property "Datasheet" "https://www.bourns.com/docs/product-datasheets/cr.pdf" (at 20.32 -17.78 0)
        (effects (font (size 1.27 1.27) (thickness 0.15)) (justify left bottom) hide)
      )
      (property "MPN" "CR0402-FX-1103GLF" (at 20.32 -20.32 0)
        (effects (font (size 1.27 1.27) (thickness 0.15)) (justify left bottom) hide)
      )
      (property "Manufacturer" "Bourns" (at 20.32 -22.86 0)
        (effects (font (size 1.27 1.27) (thickness 0.15)) (justify left bottom) hide)
      )
      (property "License" "Apache-2.0" (at 20.32 -25.4 0)
        (effects (font (size 1.27 1.27) (thickness 0.15)) (justify left bottom) hide)
      )
      (property "Author" "Antmicro" (at 20.32 -27.94 0)
        (effects (font (size 1.27 1.27) (thickness 0.15)) (justify left bottom) hide)
      )
      (property "Val" "110k" (at 20.32 -7.62 0)
        (effects (font (size 1.27 1.27) (thickness 0.15)) (justify left bottom))
      )
      (property "Tolerance" "1%" (at 20.32 -10.16 0)
        (effects (font (size 1.27 1.27)) (justify left bottom) hide)
      )
      (property "ki_keywords" "0402, SMT, RESISTOR, PASSIVE" (at 0 0 0)
        (effects (font (size 1.27 1.27)) hide)
      )
      (property "ki_description" "SMD Chip Resistor, 110 kohm, ± 1%, 63 mW, 0402 [1005 Metric], Thick Film, General Purpose" (at 0 0 0)
        (effects (font (size 1.27 1.27)) hide)
      )
      (symbol "R_110k_0402_0_1"
        (rectangle (start 0.635 0.889) (end 4.445 -0.889)
          (stroke (width 0.254) (type default))
          (fill (type none))
        )
      )
      (symbol "R_110k_0402_1_1"
        (pin passive line (at 0 0 0) (length 0.635)
          (name "~" (effects (font (size 1.27 1.27))))
          (number "1" (effects (font (size 1.27 1.27))))
        )
        (pin passive line (at 5.08 0 180) (length 0.635)
          (name "~" (effects (font (size 1.27 1.27))))
          (number "2" (effects (font (size 1.27 1.27))))
        )
      )
    )
	(symbol "antmicroResistors0402:R_124k_0402" (pin_numbers hide) (pin_names hide) (in_bom yes) (on_board yes)
      (property "Reference" "R" (at 20.32 -5.08 0)
        (effects (font (size 1.27 1.27) (thickness 0.15)) (justify left bottom))
      )
      (property "Value" "R_124k_0402" (at 20.32 -12.7 0)
        (effects (font (size 1.27 1.27) (thickness 0.15)) (justify left bottom) hide)
      )
      (property "Footprint" "antmicro-footprints:R_0402_1005Metric" (at 20.32 -15.24 0)
        (effects (font (size 1.27 1.27) (thickness 0.15)) (justify left bottom) hide)
      )
      (property "Datasheet" "https://www.bourns.com/docs/product-datasheets/cr.pdf" (at 20.32 -17.78 0)
        (effects (font (size 1.27 1.27) (thickness 0.15)) (justify left bottom) hide)
      )
      (property "MPN" "CR0402-FX-1243GLF" (at 20.32 -20.32 0)
        (effects (font (size 1.27 1.27) (thickness 0.15)) (justify left bottom) hide)
      )
      (property "Manufacturer" "Bourns" (at 20.32 -22.86 0)
        (effects (font (size 1.27 1.27) (thickness 0.15)) (justify left bottom) hide)
      )
      (property "License" "Apache-2.0" (at 20.32 -25.4 0)
        (effects (font (size 1.27 1.27) (thickness 0.15)) (justify left bottom) hide)
      )
      (property "Author" "Antmicro" (at 20.32 -27.94 0)
        (effects (font (size 1.27 1.27) (thickness 0.15)) (justify left bottom) hide)
      )
      (property "Val" "124k" (at 20.32 -7.62 0)
        (effects (font (size 1.27 1.27) (thickness 0.15)) (justify left bottom))
      )
      (property "Tolerance" "1%" (at 20.32 -10.16 0)
        (effects (font (size 1.27 1.27)) (justify left bottom) hide)
      )
      (property "ki_keywords" "0402, SMT, RESISTOR, PASSIVE" (at 0 0 0)
        (effects (font (size 1.27 1.27)) hide)
      )
      (property "ki_description" "SMD Chip Resistor, 124 kohm, ± 1%, 100 mW, 0402 [1005 Metric], Thick Film, Precision" (at 0 0 0)
        (effects (font (size 1.27 1.27)) hide)
      )
      (symbol "R_124k_0402_0_1"
        (rectangle (start 0.635 0.889) (end 4.445 -0.889)
          (stroke (width 0.254) (type default))
          (fill (type none))
        )
      )
      (symbol "R_124k_0402_1_1"
        (pin passive line (at 0 0 0) (length 0.635)
          (name "~" (effects (font (size 1.27 1.27))))
          (number "1" (effects (font (size 1.27 1.27))))
        )
        (pin passive line (at 5.08 0 180) (length 0.635)
          (name "~" (effects (font (size 1.27 1.27))))
          (number "2" (effects (font (size 1.27 1.27))))
        )
      )
    )
	(symbol "antmicroResistors0402:R_12k_0402" (pin_numbers hide) (pin_names hide) (in_bom yes) (on_board yes)
      (property "Reference" "R" (at 20.32 -5.08 0)
        (effects (font (size 1.27 1.27) (thickness 0.15)) (justify left bottom))
      )
      (property "Value" "R_12k_0402" (at 20.32 -12.7 0)
        (effects (font (size 1.27 1.27) (thickness 0.15)) (justify left bottom) hide)
      )
      (property "Footprint" "antmicro-footprints:R_0402_1005Metric" (at 20.32 -15.24 0)
        (effects (font (size 1.27 1.27) (thickness 0.15)) (justify left bottom) hide)
      )
      (property "Datasheet" "https://www.bourns.com/docs/product-datasheets/cr.pdf" (at 20.32 -17.78 0)
        (effects (font (size 1.27 1.27) (thickness 0.15)) (justify left bottom) hide)
      )
      (property "MPN" "CR0402-FX-1202GLF" (at 20.32 -20.32 0)
        (effects (font (size 1.27 1.27) (thickness 0.15)) (justify left bottom) hide)
      )
      (property "Manufacturer" "Bourns" (at 20.32 -22.86 0)
        (effects (font (size 1.27 1.27) (thickness 0.15)) (justify left bottom) hide)
      )
      (property "License" "Apache-2.0" (at 20.32 -25.4 0)
        (effects (font (size 1.27 1.27) (thickness 0.15)) (justify left bottom) hide)
      )
      (property "Author" "Antmicro" (at 20.32 -27.94 0)
        (effects (font (size 1.27 1.27) (thickness 0.15)) (justify left bottom) hide)
      )
      (property "Val" "12k" (at 20.32 -7.62 0)
        (effects (font (size 1.27 1.27) (thickness 0.15)) (justify left bottom))
      )
      (property "Tolerance" "1%" (at 20.32 -10.16 0)
        (effects (font (size 1.27 1.27)) (justify left bottom) hide)
      )
      (property "ki_keywords" "0402, SMT, RESISTOR, PASSIVE" (at 0 0 0)
        (effects (font (size 1.27 1.27)) hide)
      )
      (property "ki_description" "SMD Chip Resistor, 12 kohm, ± 1%, 62.5 mW, 0402 [1005 Metric], Thick Film, General Purpose" (at 0 0 0)
        (effects (font (size 1.27 1.27)) hide)
      )
      (symbol "R_12k_0402_0_1"
        (rectangle (start 0.635 0.889) (end 4.445 -0.889)
          (stroke (width 0.254) (type default))
          (fill (type none))
        )
      )
      (symbol "R_12k_0402_1_1"
        (pin passive line (at 0 0 0) (length 0.635)
          (name "~" (effects (font (size 1.27 1.27))))
          (number "1" (effects (font (size 1.27 1.27))))
        )
        (pin passive line (at 5.08 0 180) (length 0.635)
          (name "~" (effects (font (size 1.27 1.27))))
          (number "2" (effects (font (size 1.27 1.27))))
        )
      )
    )
	(symbol "antmicroResistors0402:R_14k_0402" (pin_numbers hide) (pin_names hide) (in_bom yes) (on_board yes)
      (property "Reference" "R" (at 20.32 -5.08 0)
        (effects (font (size 1.27 1.27) (thickness 0.15)) (justify left bottom))
      )
      (property "Value" "R_14k_0402" (at 20.32 -12.7 0)
        (effects (font (size 1.27 1.27) (thickness 0.15)) (justify left bottom) hide)
      )
      (property "Footprint" "antmicro-footprints:R_0402_1005Metric" (at 20.32 -15.24 0)
        (effects (font (size 1.27 1.27) (thickness 0.15)) (justify left bottom) hide)
      )
      (property "Datasheet" "https://www.bourns.com/docs/product-datasheets/cr.pdf" (at 20.32 -17.78 0)
        (effects (font (size 1.27 1.27) (thickness 0.15)) (justify left bottom) hide)
      )
      (property "MPN" "CR0402-FX-1402GLF" (at 20.32 -20.32 0)
        (effects (font (size 1.27 1.27) (thickness 0.15)) (justify left bottom) hide)
      )
      (property "Manufacturer" "Bourns" (at 20.32 -22.86 0)
        (effects (font (size 1.27 1.27) (thickness 0.15)) (justify left bottom) hide)
      )
      (property "License" "Apache-2.0" (at 20.32 -25.4 0)
        (effects (font (size 1.27 1.27) (thickness 0.15)) (justify left bottom) hide)
      )
      (property "Author" "Antmicro" (at 20.32 -27.94 0)
        (effects (font (size 1.27 1.27) (thickness 0.15)) (justify left bottom) hide)
      )
      (property "Val" "14k" (at 20.32 -7.62 0)
        (effects (font (size 1.27 1.27) (thickness 0.15)) (justify left bottom))
      )
      (property "Tolerance" "1%" (at 20.32 -10.16 0)
        (effects (font (size 1.27 1.27)) (justify left bottom) hide)
      )
      (property "ki_keywords" "0402, SMT, RESISTOR, PASSIVE" (at 0 0 0)
        (effects (font (size 1.27 1.27)) hide)
      )
      (property "ki_description" "SMD Chip Resistor, 14 kohm, ± 1%, 100 mW, 0402 [1005 Metric], Thick Film, Precision" (at 0 0 0)
        (effects (font (size 1.27 1.27)) hide)
      )
      (symbol "R_14k_0402_0_1"
        (rectangle (start 0.635 0.889) (end 4.445 -0.889)
          (stroke (width 0.254) (type default))
          (fill (type none))
        )
      )
      (symbol "R_14k_0402_1_1"
        (pin passive line (at 0 0 0) (length 0.635)
          (name "~" (effects (font (size 1.27 1.27))))
          (number "1" (effects (font (size 1.27 1.27))))
        )
        (pin passive line (at 5.08 0 180) (length 0.635)
          (name "~" (effects (font (size 1.27 1.27))))
          (number "2" (effects (font (size 1.27 1.27))))
        )
      )
    )
	(symbol "antmicroResistors0402:R_15k_0.1%_0402" (pin_numbers hide) (pin_names hide) (in_bom yes) (on_board yes)
      (property "Reference" "R" (at 20.32 -5.08 0)
        (effects (font (size 1.27 1.27) (thickness 0.15)) (justify left bottom))
      )
      (property "Value" "R_15k_0.1%_0402" (at 20.32 -12.7 0)
        (effects (font (size 1.27 1.27) (thickness 0.15)) (justify left bottom) hide)
      )
      (property "Footprint" "antmicro-footprints:R_0402_1005Metric" (at 20.32 -15.24 0)
        (effects (font (size 1.27 1.27) (thickness 0.15)) (justify left bottom) hide)
      )
      (property "Datasheet" "https://www.mouser.com/datasheet/2/315/AOA0000C307-1149632.pdf" (at 20.32 -17.78 0)
        (effects (font (size 1.27 1.27) (thickness 0.15)) (justify left bottom) hide)
      )
      (property "MPN" "ERA-2ARB153X" (at 20.32 -20.32 0)
        (effects (font (size 1.27 1.27) (thickness 0.15)) (justify left bottom) hide)
      )
      (property "Manufacturer" "Panasonic" (at 20.32 -22.86 0)
        (effects (font (size 1.27 1.27) (thickness 0.15)) (justify left bottom) hide)
      )
      (property "License" "Apache-2.0" (at 20.32 -25.4 0)
        (effects (font (size 1.27 1.27) (thickness 0.15)) (justify left bottom) hide)
      )
      (property "Author" "Antmicro" (at 20.32 -27.94 0)
        (effects (font (size 1.27 1.27) (thickness 0.15)) (justify left bottom) hide)
      )
      (property "Val" "15k" (at 20.32 -7.62 0)
        (effects (font (size 1.27 1.27) (thickness 0.15)) (justify left bottom))
      )
      (property "Tolerance" "0.1%" (at 20.32 -10.16 0)
        (effects (font (size 1.27 1.27)) (justify left bottom) hide)
      )
      (property "ki_keywords" "0402, SMT, RESISTOR, PASSIVE" (at 0 0 0)
        (effects (font (size 1.27 1.27)) hide)
      )
      (property "ki_description" "SMD Chip Resistor, 15 kohm, ± 0.1%, 62.5 mW, 0402 [1005 Metric], Metal Film (Thin Film)" (at 0 0 0)
        (effects (font (size 1.27 1.27)) hide)
      )
      (symbol "R_15k_0.1%_0402_0_1"
        (rectangle (start 0.635 0.889) (end 4.445 -0.889)
          (stroke (width 0.254) (type default))
          (fill (type none))
        )
      )
      (symbol "R_15k_0.1%_0402_1_1"
        (pin passive line (at 0 0 0) (length 0.635)
          (name "~" (effects (font (size 1.27 1.27))))
          (number "1" (effects (font (size 1.27 1.27))))
        )
        (pin passive line (at 5.08 0 180) (length 0.635)
          (name "~" (effects (font (size 1.27 1.27))))
          (number "2" (effects (font (size 1.27 1.27))))
        )
      )
    )
	(symbol "antmicroResistors0402:R_1M_0402" (pin_numbers hide) (pin_names hide) (in_bom yes) (on_board yes)
      (property "Reference" "R" (at 20.32 -5.08 0)
        (effects (font (size 1.27 1.27) (thickness 0.15)) (justify left bottom))
      )
      (property "Value" "R_1M_0402" (at 20.32 -12.7 0)
        (effects (font (size 1.27 1.27) (thickness 0.15)) (justify left bottom) hide)
      )
      (property "Footprint" "antmicro-footprints:R_0402_1005Metric" (at 20.32 -15.24 0)
        (effects (font (size 1.27 1.27) (thickness 0.15)) (justify left bottom) hide)
      )
      (property "Datasheet" "https://www.bourns.com/docs/product-datasheets/cr.pdf" (at 20.32 -17.78 0)
        (effects (font (size 1.27 1.27) (thickness 0.15)) (justify left bottom) hide)
      )
      (property "MPN" "CR0402-FX-1004GLF" (at 20.32 -20.32 0)
        (effects (font (size 1.27 1.27) (thickness 0.15)) (justify left bottom) hide)
      )
      (property "Manufacturer" "Bourns" (at 20.32 -22.86 0)
        (effects (font (size 1.27 1.27) (thickness 0.15)) (justify left bottom) hide)
      )
      (property "License" "Apache-2.0" (at 20.32 -25.4 0)
        (effects (font (size 1.27 1.27) (thickness 0.15)) (justify left bottom) hide)
      )
      (property "Author" "Antmicro" (at 20.32 -27.94 0)
        (effects (font (size 1.27 1.27) (thickness 0.15)) (justify left bottom) hide)
      )
      (property "Val" "1M" (at 20.32 -7.62 0)
        (effects (font (size 1.27 1.27) (thickness 0.15)) (justify left bottom))
      )
      (property "Tolerance" "1%" (at 20.32 -10.16 0)
        (effects (font (size 1.27 1.27)) (justify left bottom) hide)
      )
      (property "ki_keywords" "0402, SMT, RESISTOR, PASSIVE" (at 0 0 0)
        (effects (font (size 1.27 1.27)) hide)
      )
      (property "ki_description" "SMD Chip Resistor, 1 Mohm, ± 1%, 62.5 mW, 0402 [1005 Metric], Thick Film, General Purpose" (at 0 0 0)
        (effects (font (size 1.27 1.27)) hide)
      )
      (symbol "R_1M_0402_0_1"
        (rectangle (start 0.635 0.889) (end 4.445 -0.889)
          (stroke (width 0.254) (type default))
          (fill (type none))
        )
      )
      (symbol "R_1M_0402_1_1"
        (pin passive line (at 0 0 0) (length 0.635)
          (name "~" (effects (font (size 1.27 1.27))))
          (number "1" (effects (font (size 1.27 1.27))))
        )
        (pin passive line (at 5.08 0 180) (length 0.635)
          (name "~" (effects (font (size 1.27 1.27))))
          (number "2" (effects (font (size 1.27 1.27))))
        )
      )
    )
	(symbol "antmicroResistors0402:R_1k_0402" (pin_numbers hide) (pin_names hide) (in_bom yes) (on_board yes)
      (property "Reference" "R" (at 20.32 -5.08 0)
        (effects (font (size 1.27 1.27) (thickness 0.15)) (justify left bottom))
      )
      (property "Value" "R_1k_0402" (at 20.32 -12.7 0)
        (effects (font (size 1.27 1.27) (thickness 0.15)) (justify left bottom) hide)
      )
      (property "Footprint" "antmicro-footprints:R_0402_1005Metric" (at 20.32 -15.24 0)
        (effects (font (size 1.27 1.27) (thickness 0.15)) (justify left bottom) hide)
      )
      (property "Datasheet" "https://www.bourns.com/docs/product-datasheets/cr.pdf" (at 20.32 -17.78 0)
        (effects (font (size 1.27 1.27) (thickness 0.15)) (justify left bottom) hide)
      )
      (property "MPN" "CR0402-FX-1001GLF" (at 20.32 -20.32 0)
        (effects (font (size 1.27 1.27) (thickness 0.15)) (justify left bottom) hide)
      )
      (property "Manufacturer" "Bourns" (at 20.32 -22.86 0)
        (effects (font (size 1.27 1.27) (thickness 0.15)) (justify left bottom) hide)
      )
      (property "License" "Apache-2.0" (at 20.32 -25.4 0)
        (effects (font (size 1.27 1.27) (thickness 0.15)) (justify left bottom) hide)
      )
      (property "Author" "Antmicro" (at 20.32 -27.94 0)
        (effects (font (size 1.27 1.27) (thickness 0.15)) (justify left bottom) hide)
      )
      (property "Val" "1k" (at 20.32 -7.62 0)
        (effects (font (size 1.27 1.27) (thickness 0.15)) (justify left bottom))
      )
      (property "Tolerance" "1%" (at 20.32 -10.16 0)
        (effects (font (size 1.27 1.27)) (justify left bottom) hide)
      )
      (property "ki_keywords" "0402, SMT, RESISTOR, PASSIVE" (at 0 0 0)
        (effects (font (size 1.27 1.27)) hide)
      )
      (property "ki_description" "SMD Chip Resistor, 1 kohm, ± 1%, 63 mW, 0402 [1005 Metric], Thick Film, General Purpose" (at 0 0 0)
        (effects (font (size 1.27 1.27)) hide)
      )
      (symbol "R_1k_0402_0_1"
        (rectangle (start 0.635 0.889) (end 4.445 -0.889)
          (stroke (width 0.254) (type default))
          (fill (type none))
        )
      )
      (symbol "R_1k_0402_1_1"
        (pin passive line (at 0 0 0) (length 0.635)
          (name "~" (effects (font (size 1.27 1.27))))
          (number "1" (effects (font (size 1.27 1.27))))
        )
        (pin passive line (at 5.08 0 180) (length 0.635)
          (name "~" (effects (font (size 1.27 1.27))))
          (number "2" (effects (font (size 1.27 1.27))))
        )
      )
    )
	(symbol "antmicroResistors0402:R_24k_0402" (pin_numbers hide) (pin_names hide) (in_bom yes) (on_board yes)
      (property "Reference" "R" (at 20.32 -5.08 0)
        (effects (font (size 1.27 1.27) (thickness 0.15)) (justify left bottom))
      )
      (property "Value" "R_24k_0402" (at 20.32 -12.7 0)
        (effects (font (size 1.27 1.27) (thickness 0.15)) (justify left bottom) hide)
      )
      (property "Footprint" "antmicro-footprints:R_0402_1005Metric" (at 20.32 -15.24 0)
        (effects (font (size 1.27 1.27) (thickness 0.15)) (justify left bottom) hide)
      )
      (property "Datasheet" "https://www.bourns.com/docs/product-datasheets/cr.pdf" (at 20.32 -17.78 0)
        (effects (font (size 1.27 1.27) (thickness 0.15)) (justify left bottom) hide)
      )
      (property "MPN" "CR0402-FX-2402GLF" (at 20.32 -20.32 0)
        (effects (font (size 1.27 1.27) (thickness 0.15)) (justify left bottom) hide)
      )
      (property "Manufacturer" "Bourns" (at 20.32 -22.86 0)
        (effects (font (size 1.27 1.27) (thickness 0.15)) (justify left bottom) hide)
      )
      (property "License" "Apache-2.0" (at 20.32 -25.4 0)
        (effects (font (size 1.27 1.27) (thickness 0.15)) (justify left bottom) hide)
      )
      (property "Author" "Antmicro" (at 20.32 -27.94 0)
        (effects (font (size 1.27 1.27) (thickness 0.15)) (justify left bottom) hide)
      )
      (property "Val" "24k" (at 20.32 -7.62 0)
        (effects (font (size 1.27 1.27) (thickness 0.15)) (justify left bottom))
      )
      (property "Tolerance" "1%" (at 20.32 -10.16 0)
        (effects (font (size 1.27 1.27)) (justify left bottom) hide)
      )
      (property "ki_keywords" "0402, SMT, RESISTOR, PASSIVE" (at 0 0 0)
        (effects (font (size 1.27 1.27)) hide)
      )
      (property "ki_description" "SMD Chip Resistor, 24 kohm, ± 1%, 100 mW, 0402 [1005 Metric], Thick Film, Precision" (at 0 0 0)
        (effects (font (size 1.27 1.27)) hide)
      )
      (symbol "R_24k_0402_0_1"
        (rectangle (start 0.635 0.889) (end 4.445 -0.889)
          (stroke (width 0.254) (type default))
          (fill (type none))
        )
      )
      (symbol "R_24k_0402_1_1"
        (pin passive line (at 0 0 0) (length 0.635)
          (name "~" (effects (font (size 1.27 1.27))))
          (number "1" (effects (font (size 1.27 1.27))))
        )
        (pin passive line (at 5.08 0 180) (length 0.635)
          (name "~" (effects (font (size 1.27 1.27))))
          (number "2" (effects (font (size 1.27 1.27))))
        )
      )
    )
	(symbol "antmicroResistors0402:R_2k2_0402" (pin_numbers hide) (pin_names hide) (in_bom yes) (on_board yes)
      (property "Reference" "R" (at 20.32 -5.08 0)
        (effects (font (size 1.27 1.27) (thickness 0.15)) (justify left bottom))
      )
      (property "Value" "R_2k2_0402" (at 20.32 -12.7 0)
        (effects (font (size 1.27 1.27) (thickness 0.15)) (justify left bottom) hide)
      )
      (property "Footprint" "antmicro-footprints:R_0402_1005Metric" (at 20.32 -15.24 0)
        (effects (font (size 1.27 1.27) (thickness 0.15)) (justify left bottom) hide)
      )
      (property "Datasheet" "https://www.bourns.com/docs/product-datasheets/cr.pdf" (at 20.32 -17.78 0)
        (effects (font (size 1.27 1.27) (thickness 0.15)) (justify left bottom) hide)
      )
      (property "MPN" "CR0402-FX-2201GLF" (at 20.32 -20.32 0)
        (effects (font (size 1.27 1.27) (thickness 0.15)) (justify left bottom) hide)
      )
      (property "Manufacturer" "Bourns" (at 20.32 -22.86 0)
        (effects (font (size 1.27 1.27) (thickness 0.15)) (justify left bottom) hide)
      )
      (property "License" "Apache-2.0" (at 20.32 -25.4 0)
        (effects (font (size 1.27 1.27) (thickness 0.15)) (justify left bottom) hide)
      )
      (property "Author" "Antmicro" (at 20.32 -27.94 0)
        (effects (font (size 1.27 1.27) (thickness 0.15)) (justify left bottom) hide)
      )
      (property "Val" "2k2" (at 20.32 -7.62 0)
        (effects (font (size 1.27 1.27) (thickness 0.15)) (justify left bottom))
      )
      (property "Tolerance" "1%" (at 20.32 -10.16 0)
        (effects (font (size 1.27 1.27)) (justify left bottom) hide)
      )
      (property "ki_keywords" "0402, SMT, RESISTOR, PASSIVE" (at 0 0 0)
        (effects (font (size 1.27 1.27)) hide)
      )
      (property "ki_description" "SMD Chip Resistor, 2.2 kohm, ± 1%, 62.5 mW, 0402 [1005 Metric], Thick Film, General Purpose" (at 0 0 0)
        (effects (font (size 1.27 1.27)) hide)
      )
      (symbol "R_2k2_0402_0_1"
        (rectangle (start 0.635 0.889) (end 4.445 -0.889)
          (stroke (width 0.254) (type default))
          (fill (type none))
        )
      )
      (symbol "R_2k2_0402_1_1"
        (pin passive line (at 0 0 0) (length 0.635)
          (name "~" (effects (font (size 1.27 1.27))))
          (number "1" (effects (font (size 1.27 1.27))))
        )
        (pin passive line (at 5.08 0 180) (length 0.635)
          (name "~" (effects (font (size 1.27 1.27))))
          (number "2" (effects (font (size 1.27 1.27))))
        )
      )
    )
	(symbol "antmicroResistors0402:R_330R_0402" (pin_numbers hide) (pin_names hide) (in_bom yes) (on_board yes)
      (property "Reference" "R" (at 20.32 -5.08 0)
        (effects (font (size 1.27 1.27) (thickness 0.15)) (justify left bottom))
      )
      (property "Value" "R_330R_0402" (at 20.32 -12.7 0)
        (effects (font (size 1.27 1.27) (thickness 0.15)) (justify left bottom) hide)
      )
      (property "Footprint" "antmicro-footprints:R_0402_1005Metric" (at 20.32 -15.24 0)
        (effects (font (size 1.27 1.27) (thickness 0.15)) (justify left bottom) hide)
      )
      (property "Datasheet" "https://www.bourns.com/docs/product-datasheets/cr.pdf" (at 20.32 -17.78 0)
        (effects (font (size 1.27 1.27) (thickness 0.15)) (justify left bottom) hide)
      )
      (property "MPN" "CR0402-FX-3300GLF" (at 20.32 -20.32 0)
        (effects (font (size 1.27 1.27) (thickness 0.15)) (justify left bottom) hide)
      )
      (property "Manufacturer" "Bourns" (at 20.32 -22.86 0)
        (effects (font (size 1.27 1.27) (thickness 0.15)) (justify left bottom) hide)
      )
      (property "License" "Apache-2.0" (at 20.32 -25.4 0)
        (effects (font (size 1.27 1.27) (thickness 0.15)) (justify left bottom) hide)
      )
      (property "Author" "Antmicro" (at 20.32 -27.94 0)
        (effects (font (size 1.27 1.27) (thickness 0.15)) (justify left bottom) hide)
      )
      (property "Val" "330R" (at 20.32 -7.62 0)
        (effects (font (size 1.27 1.27) (thickness 0.15)) (justify left bottom))
      )
      (property "Tolerance" "1%" (at 20.32 -10.16 0)
        (effects (font (size 1.27 1.27)) (justify left bottom) hide)
      )
      (property "ki_keywords" "0402, SMT, RESISTOR, PASSIVE" (at 0 0 0)
        (effects (font (size 1.27 1.27)) hide)
      )
      (property "ki_description" "SMD Chip Resistor, 330 ohm, ± 1%, 62.5 mW, 0402 [1005 Metric], Thick Film, General Purpose" (at 0 0 0)
        (effects (font (size 1.27 1.27)) hide)
      )
      (symbol "R_330R_0402_0_1"
        (rectangle (start 0.635 0.889) (end 4.445 -0.889)
          (stroke (width 0.254) (type default))
          (fill (type none))
        )
      )
      (symbol "R_330R_0402_1_1"
        (pin passive line (at 0 0 0) (length 0.635)
          (name "~" (effects (font (size 1.27 1.27))))
          (number "1" (effects (font (size 1.27 1.27))))
        )
        (pin passive line (at 5.08 0 180) (length 0.635)
          (name "~" (effects (font (size 1.27 1.27))))
          (number "2" (effects (font (size 1.27 1.27))))
        )
      )
    )
	(symbol "antmicroResistors0402:R_3k01_0402" (pin_numbers hide) (pin_names hide) (in_bom yes) (on_board yes)
      (property "Reference" "R" (at 20.32 -5.08 0)
        (effects (font (size 1.27 1.27) (thickness 0.15)) (justify left bottom))
      )
      (property "Value" "R_3k01_0402" (at 20.32 -12.7 0)
        (effects (font (size 1.27 1.27) (thickness 0.15)) (justify left bottom) hide)
      )
      (property "Footprint" "antmicro-footprints:R_0402_1005Metric" (at 20.32 -15.24 0)
        (effects (font (size 1.27 1.27) (thickness 0.15)) (justify left bottom) hide)
      )
      (property "Datasheet" "https://www.bourns.com/docs/product-datasheets/cr.pdf" (at 20.32 -17.78 0)
        (effects (font (size 1.27 1.27) (thickness 0.15)) (justify left bottom) hide)
      )
      (property "MPN" "CR0402-FX-3011GLF" (at 20.32 -20.32 0)
        (effects (font (size 1.27 1.27) (thickness 0.15)) (justify left bottom) hide)
      )
      (property "Manufacturer" "Bourns" (at 20.32 -22.86 0)
        (effects (font (size 1.27 1.27) (thickness 0.15)) (justify left bottom) hide)
      )
      (property "License" "Apache-2.0" (at 20.32 -25.4 0)
        (effects (font (size 1.27 1.27) (thickness 0.15)) (justify left bottom) hide)
      )
      (property "Author" "Antmicro" (at 20.32 -27.94 0)
        (effects (font (size 1.27 1.27) (thickness 0.15)) (justify left bottom) hide)
      )
      (property "Val" "3k01" (at 20.32 -7.62 0)
        (effects (font (size 1.27 1.27) (thickness 0.15)) (justify left bottom))
      )
      (property "Tolerance" "1%" (at 20.32 -10.16 0)
        (effects (font (size 1.27 1.27)) (justify left bottom) hide)
      )
      (property "ki_keywords" "0402, SMT, RESISTOR, PASSIVE" (at 0 0 0)
        (effects (font (size 1.27 1.27)) hide)
      )
      (property "ki_description" "SMD Chip Resistor, 3.01 kohm, ± 1%, 62.5 mW, 0402 [1005 Metric], Thick Film, General Purpose" (at 0 0 0)
        (effects (font (size 1.27 1.27)) hide)
      )
      (symbol "R_3k01_0402_0_1"
        (rectangle (start 0.635 0.889) (end 4.445 -0.889)
          (stroke (width 0.254) (type default))
          (fill (type none))
        )
      )
      (symbol "R_3k01_0402_1_1"
        (pin passive line (at 0 0 0) (length 0.635)
          (name "~" (effects (font (size 1.27 1.27))))
          (number "1" (effects (font (size 1.27 1.27))))
        )
        (pin passive line (at 5.08 0 180) (length 0.635)
          (name "~" (effects (font (size 1.27 1.27))))
          (number "2" (effects (font (size 1.27 1.27))))
        )
      )
    )
	(symbol "antmicroResistors0402:R_3k3_0402" (pin_numbers hide) (pin_names hide) (in_bom yes) (on_board yes)
      (property "Reference" "R" (at 20.32 -5.08 0)
        (effects (font (size 1.27 1.27) (thickness 0.15)) (justify left bottom))
      )
      (property "Value" "R_3k3_0402" (at 20.32 -12.7 0)
        (effects (font (size 1.27 1.27) (thickness 0.15)) (justify left bottom) hide)
      )
      (property "Footprint" "antmicro-footprints:R_0402_1005Metric" (at 20.32 -15.24 0)
        (effects (font (size 1.27 1.27) (thickness 0.15)) (justify left bottom) hide)
      )
      (property "Datasheet" "https://www.bourns.com/docs/product-datasheets/cr.pdf" (at 20.32 -17.78 0)
        (effects (font (size 1.27 1.27) (thickness 0.15)) (justify left bottom) hide)
      )
      (property "MPN" "CR0402-FX-3301GLF" (at 20.32 -20.32 0)
        (effects (font (size 1.27 1.27) (thickness 0.15)) (justify left bottom) hide)
      )
      (property "Manufacturer" "Bourns" (at 20.32 -22.86 0)
        (effects (font (size 1.27 1.27) (thickness 0.15)) (justify left bottom) hide)
      )
      (property "License" "Apache-2.0" (at 20.32 -25.4 0)
        (effects (font (size 1.27 1.27) (thickness 0.15)) (justify left bottom) hide)
      )
      (property "Author" "Antmicro" (at 20.32 -27.94 0)
        (effects (font (size 1.27 1.27) (thickness 0.15)) (justify left bottom) hide)
      )
      (property "Val" "3k3" (at 20.32 -7.62 0)
        (effects (font (size 1.27 1.27) (thickness 0.15)) (justify left bottom))
      )
      (property "Tolerance" "1%" (at 20.32 -10.16 0)
        (effects (font (size 1.27 1.27)) (justify left bottom) hide)
      )
      (property "ki_keywords" "0402, SMT, RESISTOR, PASSIVE" (at 0 0 0)
        (effects (font (size 1.27 1.27)) hide)
      )
      (property "ki_description" "SMD Chip Resistor, 3.3 kohm, ± 1%, 63 mW, 0402 [1005 Metric], Thick Film, General Purpose" (at 0 0 0)
        (effects (font (size 1.27 1.27)) hide)
      )
      (symbol "R_3k3_0402_0_1"
        (rectangle (start 0.635 0.889) (end 4.445 -0.889)
          (stroke (width 0.254) (type default))
          (fill (type none))
        )
      )
      (symbol "R_3k3_0402_1_1"
        (pin passive line (at 0 0 0) (length 0.635)
          (name "~" (effects (font (size 1.27 1.27))))
          (number "1" (effects (font (size 1.27 1.27))))
        )
        (pin passive line (at 5.08 0 180) (length 0.635)
          (name "~" (effects (font (size 1.27 1.27))))
          (number "2" (effects (font (size 1.27 1.27))))
        )
      )
    )
	(symbol "antmicroResistors0402:R_40k2_0402" (pin_numbers hide) (pin_names hide) (in_bom yes) (on_board yes)
      (property "Reference" "R" (at 20.32 -5.08 0)
        (effects (font (size 1.27 1.27) (thickness 0.15)) (justify left bottom))
      )
      (property "Value" "R_40k2_0402" (at 20.32 -12.7 0)
        (effects (font (size 1.27 1.27) (thickness 0.15)) (justify left bottom) hide)
      )
      (property "Footprint" "antmicro-footprints:R_0402_1005Metric" (at 20.32 -15.24 0)
        (effects (font (size 1.27 1.27) (thickness 0.15)) (justify left bottom) hide)
      )
      (property "Datasheet" "https://www.bourns.com/docs/product-datasheets/cr.pdf" (at 20.32 -17.78 0)
        (effects (font (size 1.27 1.27) (thickness 0.15)) (justify left bottom) hide)
      )
      (property "MPN" "CR0402-FX-4022GLF" (at 20.32 -20.32 0)
        (effects (font (size 1.27 1.27) (thickness 0.15)) (justify left bottom) hide)
      )
      (property "Manufacturer" "Bourns" (at 20.32 -22.86 0)
        (effects (font (size 1.27 1.27) (thickness 0.15)) (justify left bottom) hide)
      )
      (property "License" "Apache-2.0" (at 20.32 -25.4 0)
        (effects (font (size 1.27 1.27) (thickness 0.15)) (justify left bottom) hide)
      )
      (property "Author" "Antmicro" (at 20.32 -27.94 0)
        (effects (font (size 1.27 1.27) (thickness 0.15)) (justify left bottom) hide)
      )
      (property "Val" "40k2" (at 20.32 -7.62 0)
        (effects (font (size 1.27 1.27) (thickness 0.15)) (justify left bottom))
      )
      (property "Tolerance" "1%" (at 20.32 -10.16 0)
        (effects (font (size 1.27 1.27)) (justify left bottom) hide)
      )
      (property "ki_keywords" "0402, SMT, RESISTOR, PASSIVE" (at 0 0 0)
        (effects (font (size 1.27 1.27)) hide)
      )
      (property "ki_description" "SMD Chip Resistor, 40.2 kohm, ± 1%, 63 mW, 0402 [1005 Metric], Thick Film, General Purpose" (at 0 0 0)
        (effects (font (size 1.27 1.27)) hide)
      )
      (symbol "R_40k2_0402_0_1"
        (rectangle (start 0.635 0.889) (end 4.445 -0.889)
          (stroke (width 0.254) (type default))
          (fill (type none))
        )
      )
      (symbol "R_40k2_0402_1_1"
        (pin passive line (at 0 0 0) (length 0.635)
          (name "~" (effects (font (size 1.27 1.27))))
          (number "1" (effects (font (size 1.27 1.27))))
        )
        (pin passive line (at 5.08 0 180) (length 0.635)
          (name "~" (effects (font (size 1.27 1.27))))
          (number "2" (effects (font (size 1.27 1.27))))
        )
      )
    )
	(symbol "antmicroResistors0402:R_499R_0402" (pin_numbers hide) (pin_names hide) (in_bom yes) (on_board yes)
      (property "Reference" "R" (at 20.32 -5.08 0)
        (effects (font (size 1.27 1.27) (thickness 0.15)) (justify left bottom))
      )
      (property "Value" "R_499R_0402" (at 20.32 -12.7 0)
        (effects (font (size 1.27 1.27) (thickness 0.15)) (justify left bottom) hide)
      )
      (property "Footprint" "antmicro-footprints:R_0402_1005Metric" (at 20.32 -15.24 0)
        (effects (font (size 1.27 1.27) (thickness 0.15)) (justify left bottom) hide)
      )
      (property "Datasheet" "https://www.mouser.com/datasheet/2/54/cr-1858361.pdf" (at 20.32 -17.78 0)
        (effects (font (size 1.27 1.27) (thickness 0.15)) (justify left bottom) hide)
      )
      (property "MPN" "CR0402-FX-4990GLF" (at 20.32 -20.32 0)
        (effects (font (size 1.27 1.27) (thickness 0.15)) (justify left bottom) hide)
      )
      (property "Manufacturer" "Bourns" (at 20.32 -22.86 0)
        (effects (font (size 1.27 1.27) (thickness 0.15)) (justify left bottom) hide)
      )
      (property "License" "Apache-2.0" (at 20.32 -25.4 0)
        (effects (font (size 1.27 1.27) (thickness 0.15)) (justify left bottom) hide)
      )
      (property "Author" "Antmicro" (at 20.32 -27.94 0)
        (effects (font (size 1.27 1.27) (thickness 0.15)) (justify left bottom) hide)
      )
      (property "Val" "499R" (at 20.32 -7.62 0)
        (effects (font (size 1.27 1.27) (thickness 0.15)) (justify left bottom))
      )
      (property "Tolerance" "1%" (at 20.32 -10.16 0)
        (effects (font (size 1.27 1.27)) (justify left bottom) hide)
      )
      (property "ki_keywords" "0402, SMT, RESISTOR, PASSIVE" (at 0 0 0)
        (effects (font (size 1.27 1.27)) hide)
      )
      (property "ki_description" "SMD Chip Resistor, 499 ohm, ± 1%, 63 mW, 0402 [1005 Metric], Thick Film, General Purpose" (at 0 0 0)
        (effects (font (size 1.27 1.27)) hide)
      )
      (symbol "R_499R_0402_0_1"
        (rectangle (start 0.635 0.889) (end 4.445 -0.889)
          (stroke (width 0.254) (type default))
          (fill (type none))
        )
      )
      (symbol "R_499R_0402_1_1"
        (pin passive line (at 0 0 0) (length 0.635)
          (name "~" (effects (font (size 1.27 1.27))))
          (number "1" (effects (font (size 1.27 1.27))))
        )
        (pin passive line (at 5.08 0 180) (length 0.635)
          (name "~" (effects (font (size 1.27 1.27))))
          (number "2" (effects (font (size 1.27 1.27))))
        )
      )
    )
	(symbol "antmicroResistors0402:R_4k75_0.5%_0402" (pin_numbers hide) (pin_names hide) (in_bom yes) (on_board yes)
      (property "Reference" "R" (at 20.32 -5.08 0)
        (effects (font (size 1.27 1.27) (thickness 0.15)) (justify left bottom))
      )
      (property "Value" "R_4k75_0.5%_0402" (at 20.32 -12.7 0)
        (effects (font (size 1.27 1.27) (thickness 0.15)) (justify left bottom) hide)
      )
      (property "Footprint" "antmicro-footprints:R_0402_1005Metric" (at 20.32 -15.24 0)
        (effects (font (size 1.27 1.27) (thickness 0.15)) (justify left bottom) hide)
      )
      (property "Datasheet" "https://industrial.panasonic.com/cdbs/www-data/pdf/RDQ0000/ast-ind-151033.pdf" (at 20.32 -17.78 0)
        (effects (font (size 1.27 1.27) (thickness 0.15)) (justify left bottom) hide)
      )
      (property "MPN" "ERJ-H2RD4751X" (at 20.32 -20.32 0)
        (effects (font (size 1.27 1.27) (thickness 0.15)) (justify left bottom) hide)
      )
      (property "Manufacturer" "Panasonic" (at 20.32 -22.86 0)
        (effects (font (size 1.27 1.27) (thickness 0.15)) (justify left bottom) hide)
      )
      (property "License" "Apache-2.0" (at 20.32 -25.4 0)
        (effects (font (size 1.27 1.27) (thickness 0.15)) (justify left bottom) hide)
      )
      (property "Author" "Antmicro" (at 20.32 -27.94 0)
        (effects (font (size 1.27 1.27) (thickness 0.15)) (justify left bottom) hide)
      )
      (property "Val" "4k75" (at 20.32 -7.62 0)
        (effects (font (size 1.27 1.27) (thickness 0.15)) (justify left bottom))
      )
      (property "Tolerance" "0.5%" (at 20.32 -10.16 0)
        (effects (font (size 1.27 1.27)) (justify left bottom) hide)
      )
      (property "ki_keywords" "0402, SMT, RESISTOR, PASSIVE" (at 0 0 0)
        (effects (font (size 1.27 1.27)) hide)
      )
      (property "ki_description" "SMD Chip Resistor, 4.75 kohm, ± 0.5%, 100 mW, 0402 [1005 Metric], Thick Film, High Temperature" (at 0 0 0)
        (effects (font (size 1.27 1.27)) hide)
      )
      (symbol "R_4k75_0.5%_0402_0_1"
        (rectangle (start 0.635 0.889) (end 4.445 -0.889)
          (stroke (width 0.254) (type default))
          (fill (type none))
        )
      )
      (symbol "R_4k75_0.5%_0402_1_1"
        (pin passive line (at 0 0 0) (length 0.635)
          (name "~" (effects (font (size 1.27 1.27))))
          (number "1" (effects (font (size 1.27 1.27))))
        )
        (pin passive line (at 5.08 0 180) (length 0.635)
          (name "~" (effects (font (size 1.27 1.27))))
          (number "2" (effects (font (size 1.27 1.27))))
        )
      )
    )
	(symbol "antmicroResistors0402:R_5k1_0402" (pin_numbers hide) (pin_names hide) (in_bom yes) (on_board yes)
      (property "Reference" "R" (at 20.32 -5.08 0)
        (effects (font (size 1.27 1.27) (thickness 0.15)) (justify left bottom))
      )
      (property "Value" "R_5k1_0402" (at 20.32 -12.7 0)
        (effects (font (size 1.27 1.27) (thickness 0.15)) (justify left bottom) hide)
      )
      (property "Footprint" "antmicro-footprints:R_0402_1005Metric" (at 20.32 -15.24 0)
        (effects (font (size 1.27 1.27) (thickness 0.15)) (justify left bottom) hide)
      )
      (property "Datasheet" "https://www.bourns.com/docs/product-datasheets/cr.pdf" (at 20.32 -17.78 0)
        (effects (font (size 1.27 1.27) (thickness 0.15)) (justify left bottom) hide)
      )
      (property "MPN" "CR0402-FX-5101GLF" (at 20.32 -20.32 0)
        (effects (font (size 1.27 1.27) (thickness 0.15)) (justify left bottom) hide)
      )
      (property "Manufacturer" "Bourns" (at 20.32 -22.86 0)
        (effects (font (size 1.27 1.27) (thickness 0.15)) (justify left bottom) hide)
      )
      (property "License" "Apache-2.0" (at 20.32 -25.4 0)
        (effects (font (size 1.27 1.27) (thickness 0.15)) (justify left bottom) hide)
      )
      (property "Author" "Antmicro" (at 20.32 -27.94 0)
        (effects (font (size 1.27 1.27) (thickness 0.15)) (justify left bottom) hide)
      )
      (property "Val" "5k1" (at 20.32 -7.62 0)
        (effects (font (size 1.27 1.27) (thickness 0.15)) (justify left bottom))
      )
      (property "Tolerance" "1%" (at 20.32 -10.16 0)
        (effects (font (size 1.27 1.27)) (justify left bottom) hide)
      )
      (property "ki_keywords" "0402, SMT, RESISTOR, PASSIVE" (at 0 0 0)
        (effects (font (size 1.27 1.27)) hide)
      )
      (property "ki_description" "SMD Chip Resistor, 5.1 kohm, ± 1%, 63 mW, 0402 [1005 Metric], Thick Film, General Purpose" (at 0 0 0)
        (effects (font (size 1.27 1.27)) hide)
      )
      (symbol "R_5k1_0402_0_1"
        (rectangle (start 0.635 0.889) (end 4.445 -0.889)
          (stroke (width 0.254) (type default))
          (fill (type none))
        )
      )
      (symbol "R_5k1_0402_1_1"
        (pin passive line (at 0 0 0) (length 0.635)
          (name "~" (effects (font (size 1.27 1.27))))
          (number "1" (effects (font (size 1.27 1.27))))
        )
        (pin passive line (at 5.08 0 180) (length 0.635)
          (name "~" (effects (font (size 1.27 1.27))))
          (number "2" (effects (font (size 1.27 1.27))))
        )
      )
    )
	(symbol "antmicroResistors0402:R_8k87_0402" (pin_numbers hide) (pin_names hide) (in_bom yes) (on_board yes)
      (property "Reference" "R" (at 20.32 -5.08 0)
        (effects (font (size 1.27 1.27) (thickness 0.15)) (justify left bottom))
      )
      (property "Value" "R_8k87_0402" (at 20.32 -12.7 0)
        (effects (font (size 1.27 1.27) (thickness 0.15)) (justify left bottom) hide)
      )
      (property "Footprint" "antmicro-footprints:R_0402_1005Metric" (at 20.32 -15.24 0)
        (effects (font (size 1.27 1.27) (thickness 0.15)) (justify left bottom) hide)
      )
      (property "Datasheet" "https://www.bourns.com/docs/product-datasheets/cr.pdf" (at 20.32 -17.78 0)
        (effects (font (size 1.27 1.27) (thickness 0.15)) (justify left bottom) hide)
      )
      (property "MPN" "CR0402-FX-8871GLF" (at 20.32 -20.32 0)
        (effects (font (size 1.27 1.27) (thickness 0.15)) (justify left bottom) hide)
      )
      (property "Manufacturer" "Bourns" (at 20.32 -22.86 0)
        (effects (font (size 1.27 1.27) (thickness 0.15)) (justify left bottom) hide)
      )
      (property "License" "Apache-2.0" (at 20.32 -25.4 0)
        (effects (font (size 1.27 1.27) (thickness 0.15)) (justify left bottom) hide)
      )
      (property "Author" "Antmicro" (at 20.32 -27.94 0)
        (effects (font (size 1.27 1.27) (thickness 0.15)) (justify left bottom) hide)
      )
      (property "Val" "8k87" (at 20.32 -7.62 0)
        (effects (font (size 1.27 1.27) (thickness 0.15)) (justify left bottom))
      )
      (property "Tolerance" "1%" (at 20.32 -10.16 0)
        (effects (font (size 1.27 1.27)) (justify left bottom) hide)
      )
      (property "ki_keywords" "0402, SMT, RESISTOR, PASSIVE" (at 0 0 0)
        (effects (font (size 1.27 1.27)) hide)
      )
      (property "ki_description" "SMD Chip Resistor, 8.87 kohm, ± 1%, 100 mW, 0402 [1005 Metric], Thick Film, Precision" (at 0 0 0)
        (effects (font (size 1.27 1.27)) hide)
      )
      (symbol "R_8k87_0402_0_1"
        (rectangle (start 0.635 0.889) (end 4.445 -0.889)
          (stroke (width 0.254) (type default))
          (fill (type none))
        )
      )
      (symbol "R_8k87_0402_1_1"
        (pin passive line (at 0 0 0) (length 0.635)
          (name "~" (effects (font (size 1.27 1.27))))
          (number "1" (effects (font (size 1.27 1.27))))
        )
        (pin passive line (at 5.08 0 180) (length 0.635)
          (name "~" (effects (font (size 1.27 1.27))))
          (number "2" (effects (font (size 1.27 1.27))))
        )
      )
    )
	(symbol "antmicroResistors0603:R_0R_0603" (pin_numbers hide) (pin_names hide) (in_bom yes) (on_board yes)
      (property "Reference" "R" (at 20.32 -5.08 0)
        (effects (font (size 1.27 1.27) (thickness 0.15)) (justify left bottom))
      )
      (property "Value" "R_0R_0603" (at 20.32 -12.7 0)
        (effects (font (size 1.27 1.27) (thickness 0.15)) (justify left bottom) hide)
      )
      (property "Footprint" "antmicro-footprints:R_0603_1608Metric" (at 20.32 -15.24 0)
        (effects (font (size 1.27 1.27) (thickness 0.15)) (justify left bottom) hide)
      )
      (property "Datasheet" "https://www.bourns.com/docs/product-datasheets/cr.pdf?sfvrsn=574d41f6_14" (at 20.32 -17.78 0)
        (effects (font (size 1.27 1.27) (thickness 0.15)) (justify left bottom) hide)
      )
      (property "MPN" "CR0603-J/-000ELF" (at 20.32 -20.32 0)
        (effects (font (size 1.27 1.27) (thickness 0.15)) (justify left bottom) hide)
      )
      (property "Manufacturer" "Bourns" (at 20.32 -22.86 0)
        (effects (font (size 1.27 1.27) (thickness 0.15)) (justify left bottom) hide)
      )
      (property "License" "Apache-2.0" (at 20.32 -25.4 0)
        (effects (font (size 1.27 1.27) (thickness 0.15)) (justify left bottom) hide)
      )
      (property "Author" "Antmicro" (at 20.32 -27.94 0)
        (effects (font (size 1.27 1.27) (thickness 0.15)) (justify left bottom) hide)
      )
      (property "Val" "0R" (at 20.32 -7.62 0)
        (effects (font (size 1.27 1.27) (thickness 0.15)) (justify left bottom))
      )
      (property "Tolerance" "~" (at 20.32 -10.16 0)
        (effects (font (size 1.27 1.27)) (justify left bottom) hide)
      )
      (property "Current" "1A" (at 20.32 -30.48 0)
        (effects (font (size 1.27 1.27) (thickness 0.15)) (justify left bottom) hide)
      )
      (property "ki_keywords" "0603, SMT, RESISTOR, PASSIVE" (at 0 0 0)
        (effects (font (size 1.27 1.27)) hide)
      )
      (property "ki_description" "Zero Ohm Resistor, Jumper, 0603 [1608 Metric], Thick Film, 100 mW, 1 A, Surface Mount Device, CR" (at 0 0 0)
        (effects (font (size 1.27 1.27)) hide)
      )
      (symbol "R_0R_0603_0_1"
        (rectangle (start 0.635 0.889) (end 4.445 -0.889)
          (stroke (width 0.254) (type default))
          (fill (type none))
        )
      )
      (symbol "R_0R_0603_1_1"
        (pin passive line (at 0 0 0) (length 0.635)
          (name "~" (effects (font (size 1.27 1.27))))
          (number "1" (effects (font (size 1.27 1.27))))
        )
        (pin passive line (at 5.08 0 180) (length 0.635)
          (name "~" (effects (font (size 1.27 1.27))))
          (number "2" (effects (font (size 1.27 1.27))))
        )
      )
    )
	(symbol "antmicroResistors0603:R_0R_22.4A_0603" (pin_numbers hide) (pin_names hide) (in_bom yes) (on_board yes)
      (property "Reference" "R" (at 15.24 -2.54 0)
        (effects (font (size 1.27 1.27) (thickness 0.15)) (justify left bottom))
      )
      (property "Value" "R_0R_22.4A_0603" (at 15.24 -5.08 0)
        (effects (font (size 1.27 1.27) (thickness 0.15)) (justify left bottom))
      )
      (property "Footprint" "antmicro-footprints:R_0603_1608Metric" (at 15.24 -10.16 0)
        (effects (font (size 1.27 1.27) (thickness 0.15)) (justify left bottom) hide)
      )
      (property "Datasheet" "https://fscdn.rohm.com/en/products/databook/datasheet/passive/resistor/chip_resistor/pmr-jpw-e.pdf" (at 15.24 -12.7 0)
        (effects (font (size 1.27 1.27) (thickness 0.15)) (justify left bottom) hide)
      )
      (property "MPN" "PMR03EZPJ000" (at 15.24 -15.24 0)
        (effects (font (size 1.27 1.27) (thickness 0.15)) (justify left bottom) hide)
      )
      (property "Manufacturer" "ROHM Semiconductor" (at 15.24 -17.78 0)
        (effects (font (size 1.27 1.27) (thickness 0.15)) (justify left bottom) hide)
      )
      (property "Val" "0R" (at 15.24 -7.62 0)
        (effects (font (size 1.27 1.27) (thickness 0.15)) (justify left bottom))
      )
      (property "Max. Curr." "22.4A" (at 15.24 -20.32 0)
        (effects (font (size 1.27 1.27) (thickness 0.15)) (justify left bottom))
      )
      (property "Author" "Antmicro" (at 15.24 -22.86 0)
        (effects (font (size 1.27 1.27) (thickness 0.15)) (justify left bottom) hide)
      )
      (property "License" "Apache-2.0" (at 15.24 -25.4 0)
        (effects (font (size 1.27 1.27) (thickness 0.15)) (justify left bottom) hide)
      )
      (property "Tolerance" "template_tolerance" (at 20.32 -10.16 0)
        (effects (font (size 1.27 1.27)) (justify left bottom) hide)
      )
      (property "ki_keywords" "0603, SMT, RESISTOR, PASSIVE" (at 0 0 0)
        (effects (font (size 1.27 1.27)) hide)
      )
      (property "ki_description" "SMD Chip Resistor" (at 0 0 0)
        (effects (font (size 1.27 1.27)) hide)
      )
      (symbol "R_0R_22.4A_0603_0_1"
        (rectangle (start 0.635 0.889) (end 4.445 -0.889)
          (stroke (width 0.254) (type default))
          (fill (type none))
        )
      )
      (symbol "R_0R_22.4A_0603_1_1"
        (pin passive line (at 0 0 0) (length 0.635)
          (name "~" (effects (font (size 1.27 1.27))))
          (number "1" (effects (font (size 1.27 1.27))))
        )
        (pin passive line (at 5.08 0 180) (length 0.635)
          (name "~" (effects (font (size 1.27 1.27))))
          (number "2" (effects (font (size 1.27 1.27))))
        )
      )
    )
	(symbol "antmicroResistorsmisc:R_0R02_1206" (pin_numbers hide) (pin_names hide) (in_bom yes) (on_board yes)
      (property "Reference" "R" (at 20.32 -5.08 0)
        (effects (font (size 1.27 1.27) (thickness 0.15)) (justify left bottom))
      )
      (property "Value" "R_0R02_1206" (at 20.32 -12.7 0)
        (effects (font (size 1.27 1.27) (thickness 0.15)) (justify left bottom) hide)
      )
      (property "Footprint" "antmicro-footprints:R_1206_3216Metric" (at 20.32 -15.24 0)
        (effects (font (size 1.27 1.27) (thickness 0.15)) (justify left bottom) hide)
      )
      (property "Datasheet" "https://www.mouser.com/datasheet/2/427/wslp-1763037.pdf" (at 20.32 -17.78 0)
        (effects (font (size 1.27 1.27) (thickness 0.15)) (justify left bottom) hide)
      )
      (property "MPN" "WSLP1206R0200FEA" (at 20.32 -20.32 0)
        (effects (font (size 1.27 1.27) (thickness 0.15)) (justify left bottom) hide)
      )
      (property "Manufacturer" "Vishay" (at 20.32 -22.86 0)
        (effects (font (size 1.27 1.27) (thickness 0.15)) (justify left bottom) hide)
      )
      (property "License" "Apache-2.0" (at 20.32 -25.4 0)
        (effects (font (size 1.27 1.27) (thickness 0.15)) (justify left bottom) hide)
      )
      (property "Author" "Antmicro" (at 20.32 -27.94 0)
        (effects (font (size 1.27 1.27) (thickness 0.15)) (justify left bottom) hide)
      )
      (property "Val" "0R02" (at 20.32 -7.62 0)
        (effects (font (size 1.27 1.27) (thickness 0.15)) (justify left bottom))
      )
      (property "Tolerance" "1%" (at 20.32 -10.16 0)
        (effects (font (size 1.27 1.27)) (justify left bottom) hide)
      )
      (property "ki_keywords" "1206, SMT, RESISTOR, PASSIVE" (at 0 0 0)
        (effects (font (size 1.27 1.27)) hide)
      )
      (property "ki_description" "Wirewound resistor, 0.02 ohm, 1W, ±1%" (at 0 0 0)
        (effects (font (size 1.27 1.27)) hide)
      )
      (symbol "R_0R02_1206_0_1"
        (rectangle (start 0.635 0.889) (end 4.445 -0.889)
          (stroke (width 0.254) (type default))
          (fill (type none))
        )
      )
      (symbol "R_0R02_1206_1_1"
        (pin passive line (at 0 0 0) (length 0.635)
          (name "~" (effects (font (size 1.27 1.27))))
          (number "1" (effects (font (size 1.27 1.27))))
        )
        (pin passive line (at 5.08 0 180) (length 0.635)
          (name "~" (effects (font (size 1.27 1.27))))
          (number "2" (effects (font (size 1.27 1.27))))
        )
      )
    )
	(symbol "antmicroResonators:Resonator_25MHz_ABM8G" (pin_names hide) (in_bom yes) (on_board yes)
      (property "Reference" "Y" (at 15.24 -5.08 0)
        (effects (font (size 1.27 1.27) (thickness 0.15)) (justify left bottom))
      )
      (property "Value" "Resonator_25MHz_ABM8G" (at 15.24 -12.7 0)
        (effects (font (size 1.27 1.27) (thickness 0.15)) (justify left bottom) hide)
      )
      (property "Footprint" "antmicro-footprints:Resonator_SMD_Abracon_ABM8G_3.2x2.5mm" (at 15.24 -15.24 0)
        (effects (font (size 1.27 1.27) (thickness 0.15)) (justify left bottom) hide)
      )
      (property "Datasheet" "https://abracon.com/Resonators/ABM8G.pdf" (at 15.24 -17.78 0)
        (effects (font (size 1.27 1.27) (thickness 0.15)) (justify left bottom) hide)
      )
      (property "MPN" "ABM8G-25.000MHZ-18-D2Y-T3" (at 15.24 -7.62 0)
        (effects (font (size 1.27 1.27) (thickness 0.15)) (justify left bottom))
      )
      (property "Manufacturer" "Abracon" (at 15.24 -20.32 0)
        (effects (font (size 1.27 1.27) (thickness 0.15)) (justify left bottom) hide)
      )
      (property "Author" "Antmicro" (at 15.24 -22.86 0)
        (effects (font (size 1.27 1.27) (thickness 0.15)) (justify left bottom) hide)
      )
      (property "License" "Apache-2.0" (at 15.24 -25.4 0)
        (effects (font (size 1.27 1.27) (thickness 0.15)) (justify left bottom) hide)
      )
      (property "Val" "25 MHz" (at 15.24 -10.16 0)
        (effects (font (size 1.27 1.27) (thickness 0.15)) (justify left bottom))
      )
      (property "ki_keywords" "SMT, CERAMIC, OSCILLATOR" (at 0 0 0)
        (effects (font (size 1.27 1.27)) hide)
      )
      (property "ki_description" "Crystal, 25 MHz, SMD, 3.2mm x 2.5mm, 30 ppm, 18 pF, 20 ppm, ABM8G" (at 0 0 0)
        (effects (font (size 1.27 1.27)) hide)
      )
      (symbol "Resonator_25MHz_ABM8G_1_1"
        (polyline
          (pts
            (xy 2.54 1.27)
            (xy 2.54 -1.27)
          )
          (stroke (width 0.254) (type default))
          (fill (type background))
        )
        (polyline
          (pts
            (xy 5.08 1.27)
            (xy 5.08 -1.27)
          )
          (stroke (width 0.254) (type default))
          (fill (type background))
        )
        (polyline
          (pts
            (xy 1.905 -1.905)
            (xy 1.905 -2.54)
            (xy 5.715 -2.54)
            (xy 5.715 -1.905)
          )
          (stroke (width 0.254) (type default))
          (fill (type none))
        )
        (polyline
          (pts
            (xy 1.905 1.905)
            (xy 1.905 2.54)
            (xy 5.715 2.54)
            (xy 5.715 1.905)
          )
          (stroke (width 0.254) (type default))
          (fill (type none))
        )
        (rectangle (start 3.175 1.905) (end 4.445 -1.905)
          (stroke (width 0.254) (type default))
          (fill (type background))
        )
        (pin passive line (at 0 0 0) (length 2.54)
          (name "~" (effects (font (size 1.27 1.27))))
          (number "1" (effects (font (size 1.27 1.27))))
        )
        (pin passive line (at 3.81 -5.08 90) (length 2.54)
          (name "SH" (effects (font (size 1.27 1.27))))
          (number "2" (effects (font (size 1.27 1.27))))
        )
        (pin passive line (at 7.62 0 180) (length 2.54)
          (name "~" (effects (font (size 1.27 1.27))))
          (number "3" (effects (font (size 1.27 1.27))))
        )
        (pin passive line (at 3.81 -5.08 90) (length 2.54) hide
          (name "SH" (effects (font (size 1.27 1.27))))
          (number "4" (effects (font (size 1.27 1.27))))
        )
      )
    )
	(symbol "antmicroShuntsJumpers:Net-Tie_P0.127mm" (pin_names hide) (in_bom no) (on_board yes)
      (property "Reference" "TP" (at 21.59 -5.08 0)
        (effects (font (size 1.27 1.27) (thickness 0.15)) (justify left bottom))
      )
      (property "Value" "Net-Tie_P0.127mm" (at 21.59 -7.62 0)
        (effects (font (size 1.27 1.27) (thickness 0.15)) (justify left bottom))
      )
      (property "Footprint" "antmicro-footprints:NetTie-2_SMD_Pad0.127mm" (at 21.59 -12.7 0)
        (effects (font (size 1.27 1.27) (thickness 0.15)) (justify left bottom) hide)
      )
      (property "Datasheet" "" (at 21.59 -15.24 0)
        (effects (font (size 1.27 1.27) (thickness 0.15)) (justify left bottom) hide)
      )
      (property "MPN" "" (at 21.59 -10.16 0)
        (effects (font (size 1.27 1.27) (thickness 0.15)) (justify left bottom))
      )
      (property "Manufacturer" "" (at 21.59 -17.78 0)
        (effects (font (size 1.27 1.27) (thickness 0.15)) (justify left bottom) hide)
      )
      (property "Author" "Antmicro" (at 21.59 -20.32 0)
        (effects (font (size 1.27 1.27) (thickness 0.15)) (justify left bottom) hide)
      )
      (property "License" "Apache-2.0" (at 21.59 -22.86 0)
        (effects (font (size 1.27 1.27) (thickness 0.15)) (justify left bottom) hide)
      )
      (property "ki_description" "Net tie, 2 pins" (at 0 0 0)
        (effects (font (size 1.27 1.27)) hide)
      )
      (property "ki_fp_filters" "Net*Tie*" (at 0 0 0)
        (effects (font (size 1.27 1.27)) hide)
      )
      (symbol "Net-Tie_P0.127mm_1_1"
        (polyline
          (pts
            (xy 2.54 0)
            (xy 3.81 0)
          )
          (stroke (width 0.254) (type default))
          (fill (type none))
        )
        (pin passive line (at 0 0 0) (length 2.54)
          (name "1" (effects (font (size 1.27 1.27))))
          (number "1" (effects (font (size 1.27 1.27))))
        )
        (pin passive line (at 6.35 0 180) (length 2.54)
          (name "2" (effects (font (size 1.27 1.27))))
          (number "2" (effects (font (size 1.27 1.27))))
        )
      )
    )
	(symbol "antmicroTestPoints:TP_0.75mm_SMD" (pin_names hide) (in_bom no) (on_board yes)
      (property "Reference" "TP" (at 10.16 -1.27 0)
        (effects (font (size 1.27 1.27) (thickness 0.15)) (justify left bottom))
      )
      (property "Value" "TP_0.75mm_SMD" (at 10.16 -3.81 0)
        (effects (font (size 1.27 1.27) (thickness 0.15)) (justify left bottom) hide)
      )
      (property "Footprint" "antmicro-footprints:TP_SMD_0.75mm" (at 10.16 -6.35 0)
        (effects (font (size 1.27 1.27) (thickness 0.15)) (justify left bottom) hide)
      )
      (property "Datasheet" "" (at 17.78 -12.7 0)
        (effects (font (size 1.27 1.27) (thickness 0.15)) (justify left bottom) hide)
      )
      (property "MPN" "" (at 10.795 -11.43 0)
        (effects (font (size 1.27 1.27) (thickness 0.15)) (justify left bottom) hide)
      )
      (property "Manufacturer" "" (at 10.795 -6.35 0)
        (effects (font (size 1.27 1.27) (thickness 0.15)) (justify left bottom) hide)
      )
      (property "Author" "Antmicro" (at 10.16 -8.89 0)
        (effects (font (size 1.27 1.27) (thickness 0.15)) (justify left bottom) hide)
      )
      (property "License" "Apache-2.0" (at 10.16 -11.43 0)
        (effects (font (size 1.27 1.27) (thickness 0.15)) (justify left bottom) hide)
      )
      (property "ki_keywords" "TESTPOINT" (at 0 0 0)
        (effects (font (size 1.27 1.27)) hide)
      )
      (property "ki_description" "SMT test point" (at 0 0 0)
        (effects (font (size 1.27 1.27)) hide)
      )
      (symbol "TP_0.75mm_SMD_1_1"
        (circle (center 3.175 0) (radius 0.635)
          (stroke (width 0.254) (type default))
          (fill (type none))
        )
        (pin passive line (at 0 0 0) (length 2.54)
          (name "1" (effects (font (size 1.27 1.27))))
          (number "1" (effects (font (size 1.27 1.27))))
        )
      )
    )
	(symbol "antmicroTestPoints:TP_1mm_SMD" (pin_names hide) (in_bom no) (on_board yes)
      (property "Reference" "TP" (at 15.24 -5.08 0)
        (effects (font (size 1.27 1.27) (thickness 0.15)) (justify left bottom))
      )
      (property "Value" "TP_1mm_SMD" (at 15.24 -7.62 0)
        (effects (font (size 1.27 1.27) (thickness 0.15)) (justify left bottom) hide)
      )
      (property "Footprint" "antmicro-footprints:TP_SMD_1mm" (at 15.24 -10.16 0)
        (effects (font (size 1.27 1.27) (thickness 0.15)) (justify left bottom) hide)
      )
      (property "Datasheet" "" (at 17.78 -12.7 0)
        (effects (font (size 1.27 1.27) (thickness 0.15)) (justify left bottom) hide)
      )
      (property "MPN" "" (at 0 0 0)
        (effects (font (size 1.27 1.27)) hide)
      )
      (property "Manufacturer" "" (at 0 0 0)
        (effects (font (size 1.27 1.27)) hide)
      )
      (property "Author" "Antmicro" (at 15.24 -15.24 0)
        (effects (font (size 1.27 1.27) (thickness 0.15)) (justify left bottom) hide)
      )
      (property "License" "Apache-2.0" (at 15.24 -17.78 0)
        (effects (font (size 1.27 1.27) (thickness 0.15)) (justify left bottom) hide)
      )
      (property "ki_keywords" "TESTPOINT" (at 0 0 0)
        (effects (font (size 1.27 1.27)) hide)
      )
      (property "ki_description" "Test point 1mm SMD" (at 0 0 0)
        (effects (font (size 1.27 1.27)) hide)
      )
      (symbol "TP_1mm_SMD_1_1"
        (circle (center 3.175 0) (radius 0.635)
          (stroke (width 0.254) (type default))
          (fill (type none))
        )
        (pin passive line (at 0 0 0) (length 2.54)
          (name "1" (effects (font (size 1.27 1.27))))
          (number "1" (effects (font (size 1.27 1.27))))
        )
      )
    )
	(symbol "antmicroTransistorsBipolarSingle:BC817-25W" (pin_names (offset 0) hide) (in_bom yes) (on_board yes)
      (property "Reference" "Q" (at 22.86 0 0)
        (effects (font (size 1.27 1.27) (thickness 0.15)) (justify left bottom))
      )
      (property "Value" "BC817-25W" (at 22.86 -2.54 0)
        (effects (font (size 1.27 1.27) (thickness 0.15)) (justify left bottom) hide)
      )
      (property "Footprint" "antmicro-footprints:SOT-323" (at 22.86 -5.08 0)
        (effects (font (size 1.27 1.27) (thickness 0.15)) (justify left bottom) hide)
      )
      (property "Datasheet" "https://assets.nexperia.com/documents/data-sheet/BC817W_SER.pdf" (at 22.86 -7.62 0)
        (effects (font (size 1.27 1.27) (thickness 0.15)) (justify left bottom) hide)
      )
      (property "MPN" "BC817-25W,115" (at 22.86 -10.16 0)
        (effects (font (size 1.27 1.27) (thickness 0.15)) (justify left bottom))
      )
      (property "Manufacturer" "Nexperia" (at 22.86 -12.7 0)
        (effects (font (size 1.27 1.27) (thickness 0.15)) (justify left bottom) hide)
      )
      (property "Author" "Antmicro" (at 22.86 -15.24 0)
        (effects (font (size 1.27 1.27) (thickness 0.15)) (justify left bottom) hide)
      )
      (property "License" "Apache-2.0" (at 22.86 -17.78 0)
        (effects (font (size 1.27 1.27) (thickness 0.15)) (justify left bottom) hide)
      )
      (property "ki_keywords" "SMT, TRANSISTOR, SEMICONDUCTOR, BIPOLAR" (at 0 0 0)
        (effects (font (size 1.27 1.27)) hide)
      )
      (property "ki_description" "Bipolar (BJT) Single Transistor, NPN, 45 V, 500 mA, 200 mW, SOT-323, Surface Mount" (at 0 0 0)
        (effects (font (size 1.27 1.27)) hide)
      )
      (property "ki_fp_filters" "SOT?323*" (at 0 0 0)
        (effects (font (size 1.27 1.27)) hide)
      )
      (symbol "BC817-25W_0_1"
        (polyline
          (pts
            (xy 2.54 0)
            (xy 4.445 0)
          )
          (stroke (width 0) (type default))
          (fill (type none))
        )
        (polyline
          (pts
            (xy 4.445 0.635)
            (xy 6.35 2.54)
          )
          (stroke (width 0) (type default))
          (fill (type none))
        )
        (polyline
          (pts
            (xy 4.445 -0.635)
            (xy 6.35 -2.54)
            (xy 6.35 -2.54)
          )
          (stroke (width 0) (type default))
          (fill (type none))
        )
        (polyline
          (pts
            (xy 4.445 1.905)
            (xy 4.445 -1.905)
            (xy 4.445 -1.905)
          )
          (stroke (width 0.508) (type default))
          (fill (type none))
        )
        (polyline
          (pts
            (xy 5.08 -1.778)
            (xy 5.588 -1.27)
            (xy 6.096 -2.286)
            (xy 5.08 -1.778)
            (xy 5.08 -1.778)
          )
          (stroke (width 0) (type default))
          (fill (type outline))
        )
        (circle (center 5.08 0) (radius 2.8194)
          (stroke (width 0.254) (type default))
          (fill (type none))
        )
      )
      (symbol "BC817-25W_1_1"
        (pin input line (at 0 0 0) (length 2.54)
          (name "B" (effects (font (size 1.27 1.27))))
          (number "1" (effects (font (size 1.27 1.27))))
        )
        (pin passive line (at 6.35 -5.08 90) (length 2.54)
          (name "E" (effects (font (size 1.27 1.27))))
          (number "2" (effects (font (size 1.27 1.27))))
        )
        (pin passive line (at 6.35 5.08 270) (length 2.54)
          (name "C" (effects (font (size 1.27 1.27))))
          (number "3" (effects (font (size 1.27 1.27))))
        )
      )
    )
	(symbol "antmicroTransistorsFETsMOSFETsSingle:SI7613DN-T1-GE3" (pin_names (offset 0)) (in_bom yes) (on_board yes)
      (property "Reference" "Q" (at 15.24 5.08 0)
        (effects (font (size 1.27 1.27) (thickness 0.15)) (justify left bottom))
      )
      (property "Value" "SI7613DN-T1-GE3" (at 15.24 2.54 0)
        (effects (font (size 1.27 1.27) (thickness 0.15)) (justify left bottom) hide)
      )
      (property "Footprint" "antmicro-footprints:Vishay_PowerPAK_1212-8_Single" (at 15.24 1.27 0)
        (effects (font (size 1.27 1.27) (thickness 0.15)) (justify left bottom) hide)
      )
      (property "Datasheet" "https://www.vishay.com/docs/64809/si7613dn.pdf" (at 15.24 -1.27 0)
        (effects (font (size 1.27 1.27) (thickness 0.15)) (justify left bottom) hide)
      )
      (property "MPN" "SI7613DN-T1-GE3" (at 15.24 -5.08 0)
        (effects (font (size 1.27 1.27) (thickness 0.15)) (justify left bottom))
      )
      (property "Manufacturer" "Vishay" (at 15.24 -7.62 0)
        (effects (font (size 1.27 1.27) (thickness 0.15)) (justify left bottom) hide)
      )
      (property "Author" "Antmicro" (at 15.24 -10.16 0)
        (effects (font (size 1.27 1.27) (thickness 0.15)) (justify left bottom) hide)
      )
      (property "License" "Apache-2.0" (at 15.24 -12.7 0)
        (effects (font (size 1.27 1.27) (thickness 0.15)) (justify left bottom) hide)
      )
      (property "ki_keywords" "SMT, TRANSISTOR, SEMICONDUCTOR, MOSFET, PMOS" (at 0 0 0)
        (effects (font (size 1.27 1.27)) hide)
      )
      (property "ki_description" "Power MOSFET, P Channel, 20 V, 35 A, 0.0072 ohm, PowerPAK 1212, Surface Mount" (at 0 0 0)
        (effects (font (size 1.27 1.27)) hide)
      )
      (symbol "SI7613DN-T1-GE3_1_1"
        (polyline
          (pts
            (xy 5.08 1.143)
            (xy 5.08 0.635)
          )
          (stroke (width 0.254) (type default))
          (fill (type background))
        )
        (polyline
          (pts
            (xy 5.08 1.143)
            (xy 5.08 1.651)
          )
          (stroke (width 0.254) (type default))
          (fill (type background))
        )
        (polyline
          (pts
            (xy 5.08 2.54)
            (xy 5.08 2.032)
          )
          (stroke (width 0.254) (type default))
          (fill (type background))
        )
        (polyline
          (pts
            (xy 5.08 2.54)
            (xy 5.08 3.048)
          )
          (stroke (width 0.254) (type default))
          (fill (type background))
        )
        (polyline
          (pts
            (xy 5.08 4.445)
            (xy 5.08 3.429)
          )
          (stroke (width 0.254) (type default))
          (fill (type background))
        )
        (polyline
          (pts
            (xy 7.62 1.143)
            (xy 5.08 1.143)
          )
          (stroke (width 0.254) (type default))
          (fill (type background))
        )
        (polyline
          (pts
            (xy 9.144 2.2352)
            (xy 8.128 2.2352)
          )
          (stroke (width 0.254) (type default))
          (fill (type background))
        )
        (polyline
          (pts
            (xy 2.54 0)
            (xy 4.572 0)
            (xy 4.572 3.937)
          )
          (stroke (width 0.254) (type default))
          (fill (type none))
        )
        (polyline
          (pts
            (xy 7.62 -1.27)
            (xy 7.62 2.54)
            (xy 5.08 2.54)
          )
          (stroke (width 0.254) (type default))
          (fill (type none))
        )
        (polyline
          (pts
            (xy 7.62 6.35)
            (xy 7.62 3.937)
            (xy 5.08 3.937)
          )
          (stroke (width 0.254) (type default))
          (fill (type none))
        )
        (polyline
          (pts
            (xy 7.239 2.54)
            (xy 6.477 3.048)
            (xy 6.477 2.032)
            (xy 7.239 2.54)
          )
          (stroke (width 0.254) (type default))
          (fill (type outline))
        )
        (polyline
          (pts
            (xy 8.636 2.286)
            (xy 8.128 3.048)
            (xy 9.144 3.048)
            (xy 8.636 2.286)
          )
          (stroke (width 0.254) (type default))
          (fill (type outline))
        )
        (polyline
          (pts
            (xy 7.493 0.635)
            (xy 8.636 0.635)
            (xy 8.636 3.937)
            (xy 8.636 4.445)
            (xy 7.493 4.445)
          )
          (stroke (width 0.254) (type default))
          (fill (type background))
        )
        (circle (center 6.35 2.54) (radius 3.302)
          (stroke (width 0.254) (type default))
          (fill (type background))
        )
        (circle (center 7.62 0.635) (radius 0.127)
          (stroke (width 0.254) (type default))
          (fill (type background))
        )
        (circle (center 7.62 1.143) (radius 0.127)
          (stroke (width 0.254) (type default))
          (fill (type background))
        )
        (circle (center 7.62 4.445) (radius 0.127)
          (stroke (width 0.254) (type default))
          (fill (type background))
        )
        (pin passive line (at 7.62 -3.81 90) (length 2.54)
          (name "S" (effects (font (size 1.27 1.27))))
          (number "1" (effects (font (size 1.27 1.27))))
        )
        (pin passive line (at 7.62 -3.81 90) (length 2.54) hide
          (name "S" (effects (font (size 1.27 1.27))))
          (number "2" (effects (font (size 1.27 1.27))))
        )
        (pin passive line (at 7.62 -3.81 90) (length 2.54) hide
          (name "S" (effects (font (size 1.27 1.27))))
          (number "3" (effects (font (size 1.27 1.27))))
        )
        (pin passive line (at 0 0 0) (length 2.54)
          (name "G" (effects (font (size 1.27 1.27))))
          (number "4" (effects (font (size 1.27 1.27))))
        )
        (pin passive line (at 7.62 8.89 270) (length 2.54)
          (name "D" (effects (font (size 1.27 1.27))))
          (number "5" (effects (font (size 1.27 1.27))))
        )
      )
    )
	(symbol "antmicroUSBConnectors:USB-C_JAE_DX07S024JJ2" (in_bom yes) (on_board yes)
      (property "Reference" "J" (at 36.83 2.54 0)
        (effects (font (size 1.27 1.27) (thickness 0.15)) (justify left bottom))
      )
      (property "Value" "USB-C_JAE_DX07S024JJ2" (at 36.83 0 0)
        (effects (font (size 1.27 1.27) (thickness 0.15)) (justify left bottom) hide)
      )
      (property "Footprint" "antmicro-footprints:USB-C_Receptacle_JAE_DX07S024JJ2" (at 36.83 -2.54 0)
        (effects (font (size 1.27 1.27) (thickness 0.15)) (justify left bottom) hide)
      )
      (property "Datasheet" "https://www.jae.com/en/connectors/series/detail/product/id=66508" (at 36.83 -5.08 0)
        (effects (font (size 1.27 1.27) (thickness 0.15)) (justify left bottom) hide)
      )
      (property "MPN" "DX07S024JJ2" (at 36.83 -7.62 0)
        (effects (font (size 1.27 1.27) (thickness 0.15)) (justify left bottom))
      )
      (property "Manufacturer" "JAE Electronics" (at 36.83 -10.16 0)
        (effects (font (size 1.27 1.27) (thickness 0.15)) (justify left bottom) hide)
      )
      (property "Author" "Antmicro" (at 36.83 -12.7 0)
        (effects (font (size 1.27 1.27) (thickness 0.15)) (justify left bottom) hide)
      )
      (property "License" "Apache-2.0" (at 36.83 -15.24 0)
        (effects (font (size 1.27 1.27) (thickness 0.15)) (justify left bottom) hide)
      )
      (property "ki_keywords" "USB, CONNECTOR, SMT, HORIZONTAL" (at 0 0 0)
        (effects (font (size 1.27 1.27)) hide)
      )
      (property "ki_description" "USB-C (USB TYPE-C) USB 3.2 Gen 2 (USB 3.1 Gen 2, Superspeed + (USB 3.1)) Receptacle Connector 24 Position Surface Mount, Right Angle" (at 0 0 0)
        (effects (font (size 1.27 1.27)) hide)
      )
      (symbol "USB-C_JAE_DX07S024JJ2_1_1"
        (rectangle (start -22.86 -68.58) (end -3.81 2.54)
          (stroke (width 0.254) (type default))
          (fill (type background))
        )
        (circle (center -20.066 -33.274) (radius 0.284)
          (stroke (width 0.254) (type default))
          (fill (type outline))
        )
        (circle (center -19.177 -36.068) (radius 0.5236)
          (stroke (width 0.254) (type default))
          (fill (type outline))
        )
        (rectangle (start -18.669 -33.274) (end -17.907 -32.512)
          (stroke (width 0.254) (type default))
          (fill (type outline))
        )
        (arc (start -16.51 -36.83) (mid -14.605 -38.7267) (end -12.7 -36.83)
          (stroke (width 0.254) (type default))
          (fill (type background))
        )
        (arc (start -15.24 -36.83) (mid -14.605 -37.4623) (end -13.97 -36.83)
          (stroke (width 0.254) (type default))
          (fill (type outline))
        )
        (arc (start -15.24 -36.83) (mid -14.605 -37.4623) (end -13.97 -36.83)
          (stroke (width 0.254) (type default))
          (fill (type background))
        )
        (rectangle (start -15.24 -36.83) (end -13.97 -29.21)
          (stroke (width 0.254) (type default))
          (fill (type outline))
        )
        (arc (start -13.97 -29.21) (mid -14.605 -28.5777) (end -15.24 -29.21)
          (stroke (width 0.254) (type default))
          (fill (type outline))
        )
        (arc (start -13.97 -29.21) (mid -14.605 -28.5777) (end -15.24 -29.21)
          (stroke (width 0.254) (type default))
          (fill (type background))
        )
        (arc (start -12.7 -29.21) (mid -14.605 -27.3133) (end -16.51 -29.21)
          (stroke (width 0.254) (type default))
          (fill (type background))
        )
        (polyline
          (pts
            (xy -19.177 -35.941)
            (xy -19.177 -31.623)
          )
          (stroke (width 0.254) (type default))
          (fill (type background))
        )
        (polyline
          (pts
            (xy -16.51 -36.83)
            (xy -16.51 -29.21)
          )
          (stroke (width 0.254) (type default))
          (fill (type background))
        )
        (polyline
          (pts
            (xy -12.7 -29.21)
            (xy -12.7 -36.83)
          )
          (stroke (width 0.254) (type default))
          (fill (type background))
        )
        (polyline
          (pts
            (xy -19.177 -35.179)
            (xy -20.066 -34.29)
            (xy -20.066 -33.655)
          )
          (stroke (width 0.254) (type default))
          (fill (type background))
        )
        (polyline
          (pts
            (xy -19.177 -34.798)
            (xy -18.288 -33.909)
            (xy -18.288 -33.274)
          )
          (stroke (width 0.254) (type default))
          (fill (type background))
        )
        (polyline
          (pts
            (xy -19.812 -31.623)
            (xy -19.177 -30.48)
            (xy -18.542 -31.623)
            (xy -19.812 -31.623)
          )
          (stroke (width 0.254) (type default))
          (fill (type outline))
        )
        (pin power_in line (at 0 -63.5 180) (length 3.81)
          (name "GND" (effects (font (size 1.27 1.27))))
          (number "A1" (effects (font (size 1.27 1.27))))
        )
        (pin bidirectional line (at 0 -43.18 180) (length 3.81)
          (name "RX_{2}-" (effects (font (size 1.27 1.27))))
          (number "A10" (effects (font (size 1.27 1.27))))
        )
        (pin bidirectional line (at 0 -40.64 180) (length 3.81)
          (name "RX_{2}+" (effects (font (size 1.27 1.27))))
          (number "A11" (effects (font (size 1.27 1.27))))
        )
        (pin passive line (at 0 -63.5 180) (length 3.81) hide
          (name "GND" (effects (font (size 1.27 1.27))))
          (number "A12" (effects (font (size 1.27 1.27))))
        )
        (pin bidirectional line (at 0 -33.02 180) (length 3.81)
          (name "TX_{1}+" (effects (font (size 1.27 1.27))))
          (number "A2" (effects (font (size 1.27 1.27))))
        )
        (pin bidirectional line (at 0 -35.56 180) (length 3.81)
          (name "TX_{1}-" (effects (font (size 1.27 1.27))))
          (number "A3" (effects (font (size 1.27 1.27))))
        )
        (pin passive line (at 0 0 180) (length 3.81)
          (name "VBUS" (effects (font (size 1.27 1.27))))
          (number "A4" (effects (font (size 1.27 1.27))))
        )
        (pin bidirectional line (at 0 -5.08 180) (length 3.81)
          (name "CC_{1}" (effects (font (size 1.27 1.27))))
          (number "A5" (effects (font (size 1.27 1.27))))
        )
        (pin bidirectional line (at 0 -12.7 180) (length 3.81)
          (name "D_{A}+" (effects (font (size 1.27 1.27))))
          (number "A6" (effects (font (size 1.27 1.27))))
        )
        (pin bidirectional line (at 0 -15.24 180) (length 3.81)
          (name "D_{A}-" (effects (font (size 1.27 1.27))))
          (number "A7" (effects (font (size 1.27 1.27))))
        )
        (pin bidirectional line (at 0 -55.88 180) (length 3.81)
          (name "SBU_{1}" (effects (font (size 1.27 1.27))))
          (number "A8" (effects (font (size 1.27 1.27))))
        )
        (pin passive line (at 0 0 180) (length 3.81) hide
          (name "VBUS" (effects (font (size 1.27 1.27))))
          (number "A9" (effects (font (size 1.27 1.27))))
        )
        (pin passive line (at 0 -63.5 180) (length 3.81) hide
          (name "GND" (effects (font (size 1.27 1.27))))
          (number "B1" (effects (font (size 1.27 1.27))))
        )
        (pin bidirectional line (at 0 -27.94 180) (length 3.81)
          (name "RX_{1}-" (effects (font (size 1.27 1.27))))
          (number "B10" (effects (font (size 1.27 1.27))))
        )
        (pin bidirectional line (at 0 -25.4 180) (length 3.81)
          (name "RX_{1}+" (effects (font (size 1.27 1.27))))
          (number "B11" (effects (font (size 1.27 1.27))))
        )
        (pin passive line (at 0 -63.5 180) (length 3.81) hide
          (name "GND" (effects (font (size 1.27 1.27))))
          (number "B12" (effects (font (size 1.27 1.27))))
        )
        (pin bidirectional line (at 0 -48.26 180) (length 3.81)
          (name "TX_{2}+" (effects (font (size 1.27 1.27))))
          (number "B2" (effects (font (size 1.27 1.27))))
        )
        (pin bidirectional line (at 0 -50.8 180) (length 3.81)
          (name "TX_{2}-" (effects (font (size 1.27 1.27))))
          (number "B3" (effects (font (size 1.27 1.27))))
        )
        (pin passive line (at 0 0 180) (length 3.81) hide
          (name "VBUS" (effects (font (size 1.27 1.27))))
          (number "B4" (effects (font (size 1.27 1.27))))
        )
        (pin bidirectional line (at 0 -7.62 180) (length 3.81)
          (name "CC_{2}" (effects (font (size 1.27 1.27))))
          (number "B5" (effects (font (size 1.27 1.27))))
        )
        (pin bidirectional line (at 0 -17.78 180) (length 3.81)
          (name "D_{B}+" (effects (font (size 1.27 1.27))))
          (number "B6" (effects (font (size 1.27 1.27))))
        )
        (pin bidirectional line (at 0 -20.32 180) (length 3.81)
          (name "D_{B}-" (effects (font (size 1.27 1.27))))
          (number "B7" (effects (font (size 1.27 1.27))))
        )
        (pin bidirectional line (at 0 -58.42 180) (length 3.81)
          (name "SBU_{2}" (effects (font (size 1.27 1.27))))
          (number "B8" (effects (font (size 1.27 1.27))))
        )
        (pin passive line (at 0 0 180) (length 3.81) hide
          (name "VBUS" (effects (font (size 1.27 1.27))))
          (number "B9" (effects (font (size 1.27 1.27))))
        )
        (pin passive line (at 0 -66.04 180) (length 3.81)
          (name "SH" (effects (font (size 1.27 1.27))))
          (number "SH" (effects (font (size 1.27 1.27))))
        )
      )
    )
	(symbol "antmicroWire2BoardConnectors:Molex_Nano-Fit_1x2_1053131102" (in_bom yes) (on_board yes)
      (property "Reference" "J" (at 13.335 -2.54 0)
        (effects (font (size 1.27 1.27) (thickness 0.15)) (justify left bottom))
      )
      (property "Value" "Molex_Nano-Fit_1x2_1053131102" (at 13.335 -5.08 0)
        (effects (font (size 1.27 1.27) (thickness 0.15)) (justify left bottom) hide)
      )
      (property "Footprint" "antmicro-footprints:Conn_Molex_Nano-Fit_1x2_1053131102" (at 13.335 -7.62 0)
        (effects (font (size 1.27 1.27) (thickness 0.15)) (justify left bottom) hide)
      )
      (property "Datasheet" "https://tools.molex.com/pdm_docs/ps/PS-105300-100-001.pdf" (at 13.335 -10.16 0)
        (effects (font (size 1.27 1.27) (thickness 0.15)) (justify left bottom) hide)
      )
      (property "Manufacturer" "Molex" (at 13.335 -12.7 0)
        (effects (font (size 1.27 1.27) (thickness 0.15)) (justify left bottom) hide)
      )
      (property "MPN" "1053131102" (at 13.335 -15.24 0)
        (effects (font (size 1.27 1.27) (thickness 0.15)) (justify left bottom))
      )
      (property "Author" "Antmicro" (at 13.335 -17.78 0)
        (effects (font (size 1.27 1.27) (thickness 0.15)) (justify left bottom) hide)
      )
      (property "License" "Apache-2.0" (at 13.335 -20.32 0)
        (effects (font (size 1.27 1.27) (thickness 0.15)) (justify left bottom) hide)
      )
      (property "ki_keywords" "CONNECTOR, THT" (at 0 0 0)
        (effects (font (size 1.27 1.27)) hide)
      )
      (property "ki_description" "Rectangular connector, header" (at 0 0 0)
        (effects (font (size 1.27 1.27)) hide)
      )
      (symbol "Molex_Nano-Fit_1x2_1053131102_1_1"
        (rectangle (start 2.54 -2.413) (end 3.81 -2.667)
          (stroke (width 0.254) (type default))
          (fill (type background))
        )
        (rectangle (start 2.54 0.127) (end 3.81 -0.127)
          (stroke (width 0.254) (type default))
          (fill (type background))
        )
        (rectangle (start 2.54 1.27) (end 5.08 -3.81)
          (stroke (width 0.254) (type default))
          (fill (type background))
        )
        (pin input line (at 0 0 0) (length 2.54)
          (name "~" (effects (font (size 1.27 1.27))))
          (number "1" (effects (font (size 1.27 1.27))))
        )
        (pin input line (at 0 -2.54 0) (length 2.54)
          (name "~" (effects (font (size 1.27 1.27))))
          (number "2" (effects (font (size 1.27 1.27))))
        )
      )
    )
	(symbol "antmicropower:GND" (power) (pin_numbers hide) (pin_names hide) (in_bom yes) (on_board yes)
      (property "Reference" "#PWR" (at 8.89 -2.54 0)
        (effects (font (size 1.27 1.27) (thickness 0.15)) (justify left bottom) hide)
      )
      (property "Value" "GND" (at 8.89 -5.08 0)
        (effects (font (size 1.27 1.27) (thickness 0.15)) (justify left bottom))
      )
      (property "Footprint" "" (at 8.89 -7.62 0)
        (effects (font (size 1.27 1.27) (thickness 0.15)) (justify left bottom) hide)
      )
      (property "Datasheet" "" (at 8.89 -12.7 0)
        (effects (font (size 1.27 1.27) (thickness 0.15)) (justify left bottom) hide)
      )
      (property "Author" "Antmicro" (at 8.89 -7.62 0)
        (effects (font (size 1.27 1.27) (thickness 0.15)) (justify left bottom) hide)
      )
      (property "License" "Apache-2.0" (at 8.89 -10.16 0)
        (effects (font (size 1.27 1.27) (thickness 0.15)) (justify left bottom) hide)
      )
      (symbol "GND_1_1"
        (polyline
          (pts
            (xy 0 0)
            (xy 0 -1.27)
            (xy 1.27 -1.27)
            (xy 0 -2.54)
            (xy -1.27 -1.27)
            (xy 0 -1.27)
          )
          (stroke (width 0) (type default))
          (fill (type none))
        )
        (pin power_in line (at 0 0 270) (length 0)
          (name "GND" (effects (font (size 1.27 1.27))))
          (number "1" (effects (font (size 1.27 1.27))))
        )
      )
    )
	(symbol "antmicropower:PWR_FLAG" (power) (pin_numbers hide) (pin_names (offset 0) hide) (in_bom yes) (on_board yes)
      (property "Reference" "#FLG" (at 0 1.905 0)
        (effects (font (size 1.27 1.27)) hide)
      )
      (property "Value" "PWR_FLAG" (at 0 3.81 0)
        (effects (font (size 1.27 1.27)))
      )
      (property "Footprint" "" (at 0 0 0)
        (effects (font (size 1.27 1.27)) hide)
      )
      (property "Datasheet" "" (at 0 0 0)
        (effects (font (size 1.27 1.27)) hide)
      )
      (symbol "PWR_FLAG_0_0"
        (pin power_out line (at 0 0 90) (length 0)
          (name "pwr" (effects (font (size 1.27 1.27))))
          (number "1" (effects (font (size 1.27 1.27))))
        )
      )
      (symbol "PWR_FLAG_0_1"
        (polyline
          (pts
            (xy 0 0)
            (xy 0 1.27)
            (xy -1.016 1.905)
            (xy 0 2.54)
            (xy 1.016 1.905)
            (xy 0 1.27)
          )
          (stroke (width 0) (type default))
          (fill (type none))
        )
      )
    )
)
